FILE_TYPE = MACRO_DRAWING;
SET COLOR_WIRE YELLOW;
SET COLOR_PROP ORANGE;
SET COLOR_DOT WHITE;
SET COLOR_ARC YELLOW;
SET COLOR_BODY GREEN;
SET COLOR_NOTE PURPLE;
SET PROP_DISPLAY VALUE;
SET PAGE_NUMBER P59;
FORCEADD GENOA_SP5..34
(-7975 3500);
FORCEPROP 1 LAST LOCATION U26
J 0
(-8375 6675);
DISPLAY 0.489362 (-8375 6675);
PAINT SKYBLUE (-8375 6675);
FORCEPROP 0 LAST $SEC 34
J 0
(-8350 6900);
DISPLAY 0.680851 (-8350 6900);
PAINT MONO (-8350 6900);
DISPLAY INVISIBLE (-8350 6900);
FORCEPROP 0 LAST CDS_SEC 34
J 0
(-8350 6900);
DISPLAY 1.021277 (-8350 6900);
DISPLAY INVISIBLE (-8350 6900);
FORCEPROP 0 LASTPIN (-8525 6450) $PN BL26
J 2
(-8535 6460);
DISPLAY 0.489362 (-8535 6460);
PAINT MONO (-8535 6460);
FORCEPROP 0 LASTPIN (-8525 6400) $PN BL28
J 2
(-8535 6410);
DISPLAY 0.489362 (-8535 6410);
PAINT MONO (-8535 6410);
FORCEPROP 0 LASTPIN (-8525 6350) $PN BL49
J 2
(-8535 6360);
DISPLAY 0.489362 (-8535 6360);
PAINT MONO (-8535 6360);
FORCEPROP 0 LASTPIN (-8525 6300) $PN BL51
J 2
(-8535 6310);
DISPLAY 0.489362 (-8535 6310);
PAINT MONO (-8535 6310);
FORCEPROP 0 LASTPIN (-8525 6250) $PN BL53
J 2
(-8535 6260);
DISPLAY 0.489362 (-8535 6260);
PAINT MONO (-8535 6260);
FORCEPROP 0 LASTPIN (-8525 6200) $PN BL56
J 2
(-8535 6210);
DISPLAY 0.489362 (-8535 6210);
PAINT MONO (-8535 6210);
FORCEPROP 0 LASTPIN (-8525 6150) $PN BL58
J 2
(-8535 6160);
DISPLAY 0.489362 (-8535 6160);
PAINT MONO (-8535 6160);
FORCEPROP 0 LASTPIN (-8525 6100) $PN BL61
J 2
(-8535 6110);
DISPLAY 0.489362 (-8535 6110);
PAINT MONO (-8535 6110);
FORCEPROP 0 LASTPIN (-8525 6050) $PN BL63
J 2
(-8535 6060);
DISPLAY 0.489362 (-8535 6060);
PAINT MONO (-8535 6060);
FORCEPROP 0 LASTPIN (-8525 6000) $PN BL65
J 2
(-8535 6010);
DISPLAY 0.489362 (-8535 6010);
PAINT MONO (-8535 6010);
FORCEPROP 0 LASTPIN (-8525 5950) $PN BL68
J 2
(-8535 5960);
DISPLAY 0.489362 (-8535 5960);
PAINT MONO (-8535 5960);
FORCEPROP 0 LASTPIN (-8525 5900) $PN BL70
J 2
(-8535 5910);
DISPLAY 0.489362 (-8535 5910);
PAINT MONO (-8535 5910);
FORCEPROP 0 LASTPIN (-8525 5850) $PN BL72
J 2
(-8535 5860);
DISPLAY 0.489362 (-8535 5860);
PAINT MONO (-8535 5860);
FORCEPROP 0 LASTPIN (-8525 5800) $PN BL75
J 2
(-8535 5810);
DISPLAY 0.489362 (-8535 5810);
PAINT MONO (-8535 5810);
FORCEPROP 0 LASTPIN (-8525 5750) $PN BM3
J 2
(-8535 5760);
DISPLAY 0.489362 (-8535 5760);
PAINT MONO (-8535 5760);
FORCEPROP 0 LASTPIN (-8525 5700) $PN BM8
J 2
(-8535 5710);
DISPLAY 0.489362 (-8535 5710);
PAINT MONO (-8535 5710);
FORCEPROP 0 LASTPIN (-8525 5650) $PN BM10
J 2
(-8535 5660);
DISPLAY 0.489362 (-8535 5660);
PAINT MONO (-8535 5660);
FORCEPROP 0 LASTPIN (-8525 5600) $PN BM15
J 2
(-8535 5610);
DISPLAY 0.489362 (-8535 5610);
PAINT MONO (-8535 5610);
FORCEPROP 0 LASTPIN (-8525 5550) $PN BM17
J 2
(-8535 5560);
DISPLAY 0.489362 (-8535 5560);
PAINT MONO (-8535 5560);
FORCEPROP 0 LASTPIN (-8525 5500) $PN BM23
J 2
(-8535 5510);
DISPLAY 0.489362 (-8535 5510);
PAINT MONO (-8535 5510);
FORCEPROP 0 LASTPIN (-8525 5450) $PN BM25
J 2
(-8535 5460);
DISPLAY 0.489362 (-8535 5460);
PAINT MONO (-8535 5460);
FORCEPROP 0 LASTPIN (-8525 5400) $PN BM27
J 2
(-8535 5410);
DISPLAY 0.489362 (-8535 5410);
PAINT MONO (-8535 5410);
FORCEPROP 0 LASTPIN (-8525 5350) $PN BM29
J 2
(-8535 5360);
DISPLAY 0.489362 (-8535 5360);
PAINT MONO (-8535 5360);
FORCEPROP 0 LASTPIN (-8525 5300) $PN BM31
J 2
(-8535 5310);
DISPLAY 0.489362 (-8535 5310);
PAINT MONO (-8535 5310);
FORCEPROP 0 LASTPIN (-8525 5250) $PN BM33
J 2
(-8535 5260);
DISPLAY 0.489362 (-8535 5260);
PAINT MONO (-8535 5260);
FORCEPROP 0 LASTPIN (-8525 5200) $PN BM35
J 2
(-8535 5210);
DISPLAY 0.489362 (-8535 5210);
PAINT MONO (-8535 5210);
FORCEPROP 0 LASTPIN (-8525 5150) $PN BM37
J 2
(-8535 5160);
DISPLAY 0.489362 (-8535 5160);
PAINT MONO (-8535 5160);
FORCEPROP 0 LASTPIN (-8525 5100) $PN BM40
J 2
(-8535 5110);
DISPLAY 0.489362 (-8535 5110);
PAINT MONO (-8535 5110);
FORCEPROP 0 LASTPIN (-8525 5050) $PN BM42
J 2
(-8535 5060);
DISPLAY 0.489362 (-8535 5060);
PAINT MONO (-8535 5060);
FORCEPROP 0 LASTPIN (-8525 5000) $PN BM44
J 2
(-8535 5010);
DISPLAY 0.489362 (-8535 5010);
PAINT MONO (-8535 5010);
FORCEPROP 0 LASTPIN (-8525 4950) $PN BM46
J 2
(-8535 4960);
DISPLAY 0.489362 (-8535 4960);
PAINT MONO (-8535 4960);
FORCEPROP 0 LASTPIN (-8525 4900) $PN BM48
J 2
(-8535 4910);
DISPLAY 0.489362 (-8535 4910);
PAINT MONO (-8535 4910);
FORCEPROP 0 LASTPIN (-8525 4850) $PN BM50
J 2
(-8535 4860);
DISPLAY 0.489362 (-8535 4860);
PAINT MONO (-8535 4860);
FORCEPROP 0 LASTPIN (-8525 4800) $PN BM52
J 2
(-8535 4810);
DISPLAY 0.489362 (-8535 4810);
PAINT MONO (-8535 4810);
FORCEPROP 0 LASTPIN (-8525 4750) $PN BM54
J 2
(-8535 4760);
DISPLAY 0.489362 (-8535 4760);
PAINT MONO (-8535 4760);
FORCEPROP 0 LASTPIN (-8525 4700) $PN BM59
J 2
(-8535 4710);
DISPLAY 0.489362 (-8535 4710);
PAINT MONO (-8535 4710);
FORCEPROP 0 LASTPIN (-8525 4650) $PN BM61
J 2
(-8535 4660);
DISPLAY 0.489362 (-8535 4660);
PAINT MONO (-8535 4660);
FORCEPROP 0 LASTPIN (-8525 4600) $PN BM66
J 2
(-8535 4610);
DISPLAY 0.489362 (-8535 4610);
PAINT MONO (-8535 4610);
FORCEPROP 0 LASTPIN (-8525 4550) $PN BM68
J 2
(-8535 4560);
DISPLAY 0.489362 (-8535 4560);
PAINT MONO (-8535 4560);
FORCEPROP 0 LASTPIN (-8525 4500) $PN BM73
J 2
(-8535 4510);
DISPLAY 0.489362 (-8535 4510);
PAINT MONO (-8535 4510);
FORCEPROP 0 LASTPIN (-8525 4450) $PN BN1
J 2
(-8535 4460);
DISPLAY 0.489362 (-8535 4460);
PAINT MONO (-8535 4460);
FORCEPROP 0 LASTPIN (-8525 4400) $PN BN4
J 2
(-8535 4410);
DISPLAY 0.489362 (-8535 4410);
PAINT MONO (-8535 4410);
FORCEPROP 0 LASTPIN (-8525 4350) $PN BN6
J 2
(-8535 4360);
DISPLAY 0.489362 (-8535 4360);
PAINT MONO (-8535 4360);
FORCEPROP 0 LASTPIN (-8525 4300) $PN BN8
J 2
(-8535 4310);
DISPLAY 0.489362 (-8535 4310);
PAINT MONO (-8535 4310);
FORCEPROP 0 LASTPIN (-8525 4250) $PN BN11
J 2
(-8535 4260);
DISPLAY 0.489362 (-8535 4260);
PAINT MONO (-8535 4260);
FORCEPROP 0 LASTPIN (-8525 4200) $PN BN13
J 2
(-8535 4210);
DISPLAY 0.489362 (-8535 4210);
PAINT MONO (-8535 4210);
FORCEPROP 0 LASTPIN (-8525 4150) $PN BN15
J 2
(-8535 4160);
DISPLAY 0.489362 (-8535 4160);
PAINT MONO (-8535 4160);
FORCEPROP 0 LASTPIN (-8525 4100) $PN BN18
J 2
(-8535 4110);
DISPLAY 0.489362 (-8535 4110);
PAINT MONO (-8535 4110);
FORCEPROP 0 LASTPIN (-8525 4050) $PN BN20
J 2
(-8535 4060);
DISPLAY 0.489362 (-8535 4060);
PAINT MONO (-8535 4060);
FORCEPROP 0 LASTPIN (-8525 4000) $PN BN22
J 2
(-8535 4010);
DISPLAY 0.489362 (-8535 4010);
PAINT MONO (-8535 4010);
FORCEPROP 0 LASTPIN (-8525 3950) $PN BN24
J 2
(-8535 3960);
DISPLAY 0.489362 (-8535 3960);
PAINT MONO (-8535 3960);
FORCEPROP 0 LASTPIN (-8525 3900) $PN BN26
J 2
(-8535 3910);
DISPLAY 0.489362 (-8535 3910);
PAINT MONO (-8535 3910);
FORCEPROP 0 LASTPIN (-8525 3850) $PN BN28
J 2
(-8535 3860);
DISPLAY 0.489362 (-8535 3860);
PAINT MONO (-8535 3860);
FORCEPROP 0 LASTPIN (-8525 3800) $PN BN30
J 2
(-8535 3810);
DISPLAY 0.489362 (-8535 3810);
PAINT MONO (-8535 3810);
FORCEPROP 0 LASTPIN (-8525 3750) $PN BN32
J 2
(-8535 3760);
DISPLAY 0.489362 (-8535 3760);
PAINT MONO (-8535 3760);
FORCEPROP 0 LASTPIN (-8525 3700) $PN BN34
J 2
(-8535 3710);
DISPLAY 0.489362 (-8535 3710);
PAINT MONO (-8535 3710);
FORCEPROP 0 LASTPIN (-8525 3650) $PN BN36
J 2
(-8535 3660);
DISPLAY 0.489362 (-8535 3660);
PAINT MONO (-8535 3660);
FORCEPROP 0 LASTPIN (-8525 3600) $PN BN41
J 2
(-8535 3610);
DISPLAY 0.489362 (-8535 3610);
PAINT MONO (-8535 3610);
FORCEPROP 0 LASTPIN (-8525 3550) $PN BN43
J 2
(-8535 3560);
DISPLAY 0.489362 (-8535 3560);
PAINT MONO (-8535 3560);
FORCEPROP 0 LASTPIN (-8525 3500) $PN BN45
J 2
(-8535 3510);
DISPLAY 0.489362 (-8535 3510);
PAINT MONO (-8535 3510);
FORCEPROP 0 LASTPIN (-8525 3450) $PN BN47
J 2
(-8535 3460);
DISPLAY 0.489362 (-8535 3460);
PAINT MONO (-8535 3460);
FORCEPROP 0 LASTPIN (-8525 3400) $PN BN49
J 2
(-8535 3410);
DISPLAY 0.489362 (-8535 3410);
PAINT MONO (-8535 3410);
FORCEPROP 0 LASTPIN (-8525 3350) $PN BN51
J 2
(-8535 3360);
DISPLAY 0.489362 (-8535 3360);
PAINT MONO (-8535 3360);
FORCEPROP 0 LASTPIN (-8525 3300) $PN BN53
J 2
(-8535 3310);
DISPLAY 0.489362 (-8535 3310);
PAINT MONO (-8535 3310);
FORCEPROP 0 LASTPIN (-8525 3250) $PN BN56
J 2
(-8535 3260);
DISPLAY 0.489362 (-8535 3260);
PAINT MONO (-8535 3260);
FORCEPROP 0 LASTPIN (-8525 3200) $PN BN58
J 2
(-8535 3210);
DISPLAY 0.489362 (-8535 3210);
PAINT MONO (-8535 3210);
FORCEPROP 0 LASTPIN (-8525 3150) $PN BN61
J 2
(-8535 3160);
DISPLAY 0.489362 (-8535 3160);
PAINT MONO (-8535 3160);
FORCEPROP 0 LASTPIN (-8525 3100) $PN BN63
J 2
(-8535 3110);
DISPLAY 0.489362 (-8535 3110);
PAINT MONO (-8535 3110);
FORCEPROP 0 LASTPIN (-8525 3050) $PN BN65
J 2
(-8535 3060);
DISPLAY 0.489362 (-8535 3060);
PAINT MONO (-8535 3060);
FORCEPROP 0 LASTPIN (-8525 3000) $PN BN68
J 2
(-8535 3010);
DISPLAY 0.489362 (-8535 3010);
PAINT MONO (-8535 3010);
FORCEPROP 0 LASTPIN (-8525 2950) $PN BN70
J 2
(-8535 2960);
DISPLAY 0.489362 (-8535 2960);
PAINT MONO (-8535 2960);
FORCEPROP 0 LASTPIN (-8525 2900) $PN BN72
J 2
(-8535 2910);
DISPLAY 0.489362 (-8535 2910);
PAINT MONO (-8535 2910);
FORCEPROP 0 LASTPIN (-8525 2850) $PN BN75
J 2
(-8535 2860);
DISPLAY 0.489362 (-8535 2860);
PAINT MONO (-8535 2860);
FORCEPROP 0 LASTPIN (-8525 2800) $PN BP3
J 2
(-8535 2810);
DISPLAY 0.489362 (-8535 2810);
PAINT MONO (-8535 2810);
FORCEPROP 0 LASTPIN (-8525 2750) $PN BP5
J 2
(-8535 2760);
DISPLAY 0.489362 (-8535 2760);
PAINT MONO (-8535 2760);
FORCEPROP 0 LASTPIN (-8525 2700) $PN BP8
J 2
(-8535 2710);
DISPLAY 0.489362 (-8535 2710);
PAINT MONO (-8535 2710);
FORCEPROP 0 LASTPIN (-8525 2650) $PN BP10
J 2
(-8535 2660);
DISPLAY 0.489362 (-8535 2660);
PAINT MONO (-8535 2660);
FORCEPROP 0 LASTPIN (-8525 2600) $PN BP12
J 2
(-8535 2610);
DISPLAY 0.489362 (-8535 2610);
PAINT MONO (-8535 2610);
FORCEPROP 0 LASTPIN (-8525 2550) $PN BP15
J 2
(-8535 2560);
DISPLAY 0.489362 (-8535 2560);
PAINT MONO (-8535 2560);
FORCEPROP 0 LASTPIN (-8525 2500) $PN BP17
J 2
(-8535 2510);
DISPLAY 0.489362 (-8535 2510);
PAINT MONO (-8535 2510);
FORCEPROP 0 LASTPIN (-8525 2450) $PN BP19
J 2
(-8535 2460);
DISPLAY 0.489362 (-8535 2460);
PAINT MONO (-8535 2460);
FORCEPROP 0 LASTPIN (-8525 2400) $PN BP23
J 2
(-8535 2410);
DISPLAY 0.489362 (-8535 2410);
PAINT MONO (-8535 2410);
FORCEPROP 0 LASTPIN (-8525 2350) $PN BP25
J 2
(-8535 2360);
DISPLAY 0.489362 (-8535 2360);
PAINT MONO (-8535 2360);
FORCEPROP 0 LASTPIN (-8525 2300) $PN BP27
J 2
(-8535 2310);
DISPLAY 0.489362 (-8535 2310);
PAINT MONO (-8535 2310);
FORCEPROP 0 LASTPIN (-8525 2250) $PN BP29
J 2
(-8535 2260);
DISPLAY 0.489362 (-8535 2260);
PAINT MONO (-8535 2260);
FORCEPROP 0 LASTPIN (-8525 2200) $PN BP31
J 2
(-8535 2210);
DISPLAY 0.489362 (-8535 2210);
PAINT MONO (-8535 2210);
FORCEPROP 0 LASTPIN (-8525 2150) $PN BP33
J 2
(-8535 2160);
DISPLAY 0.489362 (-8535 2160);
PAINT MONO (-8535 2160);
FORCEPROP 0 LASTPIN (-8525 2100) $PN BP35
J 2
(-8535 2110);
DISPLAY 0.489362 (-8535 2110);
PAINT MONO (-8535 2110);
FORCEPROP 0 LASTPIN (-8525 2050) $PN BP37
J 2
(-8535 2060);
DISPLAY 0.489362 (-8535 2060);
PAINT MONO (-8535 2060);
FORCEPROP 0 LASTPIN (-8525 2000) $PN BP40
J 2
(-8535 2010);
DISPLAY 0.489362 (-8535 2010);
PAINT MONO (-8535 2010);
FORCEPROP 0 LASTPIN (-8525 1950) $PN BP42
J 2
(-8535 1960);
DISPLAY 0.489362 (-8535 1960);
PAINT MONO (-8535 1960);
FORCEPROP 0 LASTPIN (-8525 1900) $PN BP44
J 2
(-8535 1910);
DISPLAY 0.489362 (-8535 1910);
PAINT MONO (-8535 1910);
FORCEPROP 0 LASTPIN (-8525 1850) $PN BP46
J 2
(-8535 1860);
DISPLAY 0.489362 (-8535 1860);
PAINT MONO (-8535 1860);
FORCEPROP 0 LASTPIN (-8525 1800) $PN BP48
J 2
(-8535 1810);
DISPLAY 0.489362 (-8535 1810);
PAINT MONO (-8535 1810);
FORCEPROP 0 LASTPIN (-8525 1750) $PN BP50
J 2
(-8535 1760);
DISPLAY 0.489362 (-8535 1760);
PAINT MONO (-8535 1760);
FORCEPROP 0 LASTPIN (-8525 1700) $PN BP52
J 2
(-8535 1710);
DISPLAY 0.489362 (-8535 1710);
PAINT MONO (-8535 1710);
FORCEPROP 0 LASTPIN (-8525 1650) $PN BP54
J 2
(-8535 1660);
DISPLAY 0.489362 (-8535 1660);
PAINT MONO (-8535 1660);
FORCEPROP 0 LASTPIN (-8525 1600) $PN BP57
J 2
(-8535 1610);
DISPLAY 0.489362 (-8535 1610);
PAINT MONO (-8535 1610);
FORCEPROP 0 LASTPIN (-8525 1550) $PN BP59
J 2
(-8535 1560);
DISPLAY 0.489362 (-8535 1560);
PAINT MONO (-8535 1560);
FORCEPROP 0 LASTPIN (-8525 1500) $PN BP61
J 2
(-8535 1510);
DISPLAY 0.489362 (-8535 1510);
PAINT MONO (-8535 1510);
FORCEPROP 0 LASTPIN (-8525 1450) $PN BP64
J 2
(-8535 1460);
DISPLAY 0.489362 (-8535 1460);
PAINT MONO (-8535 1460);
FORCEPROP 0 LASTPIN (-8525 1400) $PN BP66
J 2
(-8535 1410);
DISPLAY 0.489362 (-8535 1410);
PAINT MONO (-8535 1410);
FORCEPROP 0 LASTPIN (-8525 1350) $PN BP68
J 2
(-8535 1360);
DISPLAY 0.489362 (-8535 1360);
PAINT MONO (-8535 1360);
FORCEPROP 0 LASTPIN (-8525 1300) $PN BP71
J 2
(-8535 1310);
DISPLAY 0.489362 (-8535 1310);
PAINT MONO (-8535 1310);
FORCEPROP 0 LASTPIN (-8525 1250) $PN BP73
J 2
(-8535 1260);
DISPLAY 0.489362 (-8535 1260);
PAINT MONO (-8535 1260);
FORCEPROP 0 LASTPIN (-8525 1200) $PN BR1
J 2
(-8535 1210);
DISPLAY 0.489362 (-8535 1210);
PAINT MONO (-8535 1210);
FORCEPROP 0 LASTPIN (-8525 1150) $PN BR3
J 2
(-8535 1160);
DISPLAY 0.489362 (-8535 1160);
PAINT MONO (-8535 1160);
FORCEPROP 0 LASTPIN (-8525 1100) $PN BR6
J 2
(-8535 1110);
DISPLAY 0.489362 (-8535 1110);
PAINT MONO (-8535 1110);
FORCEPROP 0 LASTPIN (-8525 1050) $PN BR7
J 2
(-8535 1060);
DISPLAY 0.489362 (-8535 1060);
PAINT MONO (-8535 1060);
FORCEPROP 0 LASTPIN (-8525 1000) $PN BR8
J 2
(-8535 1010);
DISPLAY 0.489362 (-8535 1010);
PAINT MONO (-8535 1010);
FORCEPROP 0 LASTPIN (-8525 950) $PN BR10
J 2
(-8535 960);
DISPLAY 0.489362 (-8535 960);
PAINT MONO (-8535 960);
FORCEPROP 0 LASTPIN (-8525 900) $PN BR13
J 2
(-8535 910);
DISPLAY 0.489362 (-8535 910);
PAINT MONO (-8535 910);
FORCEPROP 0 LASTPIN (-8525 850) $PN BR14
J 2
(-8535 860);
DISPLAY 0.489362 (-8535 860);
PAINT MONO (-8535 860);
FORCEPROP 0 LASTPIN (-8525 800) $PN BR15
J 2
(-8535 810);
DISPLAY 0.489362 (-8535 810);
PAINT MONO (-8535 810);
FORCEPROP 0 LASTPIN (-8525 750) $PN BR17
J 2
(-8535 760);
DISPLAY 0.489362 (-8535 760);
PAINT MONO (-8535 760);
FORCEPROP 0 LASTPIN (-8525 700) $PN BR20
J 2
(-8535 710);
DISPLAY 0.489362 (-8535 710);
PAINT MONO (-8535 710);
FORCEPROP 0 LASTPIN (-8525 650) $PN BR21
J 2
(-8535 660);
DISPLAY 0.489362 (-8535 660);
PAINT MONO (-8535 660);
FORCEPROP 0 LASTPIN (-8525 600) $PN BR22
J 2
(-8535 610);
DISPLAY 0.489362 (-8535 610);
PAINT MONO (-8535 610);
FORCEPROP 0 LASTPIN (-8525 550) $PN BR24
J 2
(-8535 560);
DISPLAY 0.489362 (-8535 560);
PAINT MONO (-8535 560);
FORCEPROP 0 LASTPIN (-7425 6450) $PN BR26
J 0
(-7415 6460);
DISPLAY 0.489362 (-7415 6460);
PAINT MONO (-7415 6460);
FORCEPROP 0 LASTPIN (-7425 6400) $PN BR28
J 0
(-7415 6410);
DISPLAY 0.489362 (-7415 6410);
PAINT MONO (-7415 6410);
FORCEPROP 0 LASTPIN (-7425 6350) $PN BR30
J 0
(-7415 6360);
DISPLAY 0.489362 (-7415 6360);
PAINT MONO (-7415 6360);
FORCEPROP 0 LASTPIN (-7425 6300) $PN BR32
J 0
(-7415 6310);
DISPLAY 0.489362 (-7415 6310);
PAINT MONO (-7415 6310);
FORCEPROP 0 LASTPIN (-7425 6250) $PN BR34
J 0
(-7415 6260);
DISPLAY 0.489362 (-7415 6260);
PAINT MONO (-7415 6260);
FORCEPROP 0 LASTPIN (-7425 6200) $PN BR36
J 0
(-7415 6210);
DISPLAY 0.489362 (-7415 6210);
PAINT MONO (-7415 6210);
FORCEPROP 0 LASTPIN (-7425 6150) $PN BR41
J 0
(-7415 6160);
DISPLAY 0.489362 (-7415 6160);
PAINT MONO (-7415 6160);
FORCEPROP 0 LASTPIN (-7425 6100) $PN BR43
J 0
(-7415 6110);
DISPLAY 0.489362 (-7415 6110);
PAINT MONO (-7415 6110);
FORCEPROP 0 LASTPIN (-7425 6050) $PN BR45
J 0
(-7415 6060);
DISPLAY 0.489362 (-7415 6060);
PAINT MONO (-7415 6060);
FORCEPROP 0 LASTPIN (-7425 6000) $PN BR47
J 0
(-7415 6010);
DISPLAY 0.489362 (-7415 6010);
PAINT MONO (-7415 6010);
FORCEPROP 0 LASTPIN (-7425 5950) $PN BR49
J 0
(-7415 5960);
DISPLAY 0.489362 (-7415 5960);
PAINT MONO (-7415 5960);
FORCEPROP 0 LASTPIN (-7425 5900) $PN BR51
J 0
(-7415 5910);
DISPLAY 0.489362 (-7415 5910);
PAINT MONO (-7415 5910);
FORCEPROP 0 LASTPIN (-7425 5850) $PN BR55
J 0
(-7415 5860);
DISPLAY 0.489362 (-7415 5860);
PAINT MONO (-7415 5860);
FORCEPROP 0 LASTPIN (-7425 5800) $PN BR56
J 0
(-7415 5810);
DISPLAY 0.489362 (-7415 5810);
PAINT MONO (-7415 5810);
FORCEPROP 0 LASTPIN (-7425 5750) $PN BR59
J 0
(-7415 5760);
DISPLAY 0.489362 (-7415 5760);
PAINT MONO (-7415 5760);
FORCEPROP 0 LASTPIN (-7425 5700) $PN BR61
J 0
(-7415 5710);
DISPLAY 0.489362 (-7415 5710);
PAINT MONO (-7415 5710);
FORCEPROP 0 LASTPIN (-7425 5650) $PN BR62
J 0
(-7415 5660);
DISPLAY 0.489362 (-7415 5660);
PAINT MONO (-7415 5660);
FORCEPROP 0 LASTPIN (-7425 5600) $PN BR63
J 0
(-7415 5610);
DISPLAY 0.489362 (-7415 5610);
PAINT MONO (-7415 5610);
FORCEPROP 0 LASTPIN (-7425 5550) $PN BR66
J 0
(-7415 5560);
DISPLAY 0.489362 (-7415 5560);
PAINT MONO (-7415 5560);
FORCEPROP 0 LASTPIN (-7425 5500) $PN BR68
J 0
(-7415 5510);
DISPLAY 0.489362 (-7415 5510);
PAINT MONO (-7415 5510);
FORCEPROP 0 LASTPIN (-7425 5450) $PN BR69
J 0
(-7415 5460);
DISPLAY 0.489362 (-7415 5460);
PAINT MONO (-7415 5460);
FORCEPROP 0 LASTPIN (-7425 5400) $PN BR70
J 0
(-7415 5410);
DISPLAY 0.489362 (-7415 5410);
PAINT MONO (-7415 5410);
FORCEPROP 0 LASTPIN (-7425 5350) $PN BR73
J 0
(-7415 5360);
DISPLAY 0.489362 (-7415 5360);
PAINT MONO (-7415 5360);
FORCEPROP 0 LASTPIN (-7425 5300) $PN BR75
J 0
(-7415 5310);
DISPLAY 0.489362 (-7415 5310);
PAINT MONO (-7415 5310);
FORCEPROP 0 LASTPIN (-7425 5250) $PN BT3
J 0
(-7415 5260);
DISPLAY 0.489362 (-7415 5260);
PAINT MONO (-7415 5260);
FORCEPROP 0 LASTPIN (-7425 5200) $PN BT4
J 0
(-7415 5210);
DISPLAY 0.489362 (-7415 5210);
PAINT MONO (-7415 5210);
FORCEPROP 0 LASTPIN (-7425 5150) $PN BT5
J 0
(-7415 5160);
DISPLAY 0.489362 (-7415 5160);
PAINT MONO (-7415 5160);
FORCEPROP 0 LASTPIN (-7425 5100) $PN BT7
J 0
(-7415 5110);
DISPLAY 0.489362 (-7415 5110);
PAINT MONO (-7415 5110);
FORCEPROP 0 LASTPIN (-7425 5050) $PN BT8
J 0
(-7415 5060);
DISPLAY 0.489362 (-7415 5060);
PAINT MONO (-7415 5060);
FORCEPROP 0 LASTPIN (-7425 5000) $PN BT10
J 0
(-7415 5010);
DISPLAY 0.489362 (-7415 5010);
PAINT MONO (-7415 5010);
FORCEPROP 0 LASTPIN (-7425 4950) $PN BT11
J 0
(-7415 4960);
DISPLAY 0.489362 (-7415 4960);
PAINT MONO (-7415 4960);
FORCEPROP 0 LASTPIN (-7425 4900) $PN BT12
J 0
(-7415 4910);
DISPLAY 0.489362 (-7415 4910);
PAINT MONO (-7415 4910);
FORCEPROP 0 LASTPIN (-7425 4850) $PN BT14
J 0
(-7415 4860);
DISPLAY 0.489362 (-7415 4860);
PAINT MONO (-7415 4860);
FORCEPROP 0 LASTPIN (-7425 4800) $PN BT15
J 0
(-7415 4810);
DISPLAY 0.489362 (-7415 4810);
PAINT MONO (-7415 4810);
FORCEPROP 0 LASTPIN (-7425 4750) $PN BT17
J 0
(-7415 4760);
DISPLAY 0.489362 (-7415 4760);
PAINT MONO (-7415 4760);
FORCEPROP 0 LASTPIN (-7425 4700) $PN BT18
J 0
(-7415 4710);
DISPLAY 0.489362 (-7415 4710);
PAINT MONO (-7415 4710);
FORCEPROP 0 LASTPIN (-7425 4650) $PN BT19
J 0
(-7415 4660);
DISPLAY 0.489362 (-7415 4660);
PAINT MONO (-7415 4660);
FORCEPROP 0 LASTPIN (-7425 4600) $PN BT21
J 0
(-7415 4610);
DISPLAY 0.489362 (-7415 4610);
PAINT MONO (-7415 4610);
FORCEPROP 0 LASTPIN (-7425 4550) $PN BT22
J 0
(-7415 4560);
DISPLAY 0.489362 (-7415 4560);
PAINT MONO (-7415 4560);
FORCEPROP 0 LASTPIN (-7425 4500) $PN BT25
J 0
(-7415 4510);
DISPLAY 0.489362 (-7415 4510);
PAINT MONO (-7415 4510);
FORCEPROP 0 LASTPIN (-7425 4450) $PN BT28
J 0
(-7415 4460);
DISPLAY 0.489362 (-7415 4460);
PAINT MONO (-7415 4460);
FORCEPROP 0 LASTPIN (-7425 4400) $PN BT31
J 0
(-7415 4410);
DISPLAY 0.489362 (-7415 4410);
PAINT MONO (-7415 4410);
FORCEPROP 0 LASTPIN (-7425 4350) $PN BT34
J 0
(-7415 4360);
DISPLAY 0.489362 (-7415 4360);
PAINT MONO (-7415 4360);
FORCEPROP 0 LASTPIN (-7425 4300) $PN BT37
J 0
(-7415 4310);
DISPLAY 0.489362 (-7415 4310);
PAINT MONO (-7415 4310);
FORCEPROP 0 LASTPIN (-7425 4250) $PN BT39
J 0
(-7415 4260);
DISPLAY 0.489362 (-7415 4260);
PAINT MONO (-7415 4260);
FORCEPROP 0 LASTPIN (-7425 4200) $PN BT42
J 0
(-7415 4210);
DISPLAY 0.489362 (-7415 4210);
PAINT MONO (-7415 4210);
FORCEPROP 0 LASTPIN (-7425 4150) $PN BT45
J 0
(-7415 4160);
DISPLAY 0.489362 (-7415 4160);
PAINT MONO (-7415 4160);
FORCEPROP 0 LASTPIN (-7425 4100) $PN BT48
J 0
(-7415 4110);
DISPLAY 0.489362 (-7415 4110);
PAINT MONO (-7415 4110);
FORCEPROP 0 LASTPIN (-7425 4050) $PN BT51
J 0
(-7415 4060);
DISPLAY 0.489362 (-7415 4060);
PAINT MONO (-7415 4060);
FORCEPROP 0 LASTPIN (-7425 4000) $PN BT54
J 0
(-7415 4010);
DISPLAY 0.489362 (-7415 4010);
PAINT MONO (-7415 4010);
FORCEPROP 0 LASTPIN (-7425 3950) $PN BT55
J 0
(-7415 3960);
DISPLAY 0.489362 (-7415 3960);
PAINT MONO (-7415 3960);
FORCEPROP 0 LASTPIN (-7425 3900) $PN BT57
J 0
(-7415 3910);
DISPLAY 0.489362 (-7415 3910);
PAINT MONO (-7415 3910);
FORCEPROP 0 LASTPIN (-7425 3850) $PN BT58
J 0
(-7415 3860);
DISPLAY 0.489362 (-7415 3860);
PAINT MONO (-7415 3860);
FORCEPROP 0 LASTPIN (-7425 3800) $PN BT59
J 0
(-7415 3810);
DISPLAY 0.489362 (-7415 3810);
PAINT MONO (-7415 3810);
FORCEPROP 0 LASTPIN (-7425 3750) $PN BT61
J 0
(-7415 3760);
DISPLAY 0.489362 (-7415 3760);
PAINT MONO (-7415 3760);
FORCEPROP 0 LASTPIN (-7425 3700) $PN BT62
J 0
(-7415 3710);
DISPLAY 0.489362 (-7415 3710);
PAINT MONO (-7415 3710);
FORCEPROP 0 LASTPIN (-7425 3650) $PN BT64
J 0
(-7415 3660);
DISPLAY 0.489362 (-7415 3660);
PAINT MONO (-7415 3660);
FORCEPROP 0 LASTPIN (-7425 3600) $PN BT65
J 0
(-7415 3610);
DISPLAY 0.489362 (-7415 3610);
PAINT MONO (-7415 3610);
FORCEPROP 0 LASTPIN (-7425 3550) $PN BT66
J 0
(-7415 3560);
DISPLAY 0.489362 (-7415 3560);
PAINT MONO (-7415 3560);
FORCEPROP 0 LASTPIN (-7425 3500) $PN BT68
J 0
(-7415 3510);
DISPLAY 0.489362 (-7415 3510);
PAINT MONO (-7415 3510);
FORCEPROP 0 LASTPIN (-7425 3450) $PN BT69
J 0
(-7415 3460);
DISPLAY 0.489362 (-7415 3460);
PAINT MONO (-7415 3460);
FORCEPROP 0 LASTPIN (-7425 3400) $PN BT71
J 0
(-7415 3410);
DISPLAY 0.489362 (-7415 3410);
PAINT MONO (-7415 3410);
FORCEPROP 0 LASTPIN (-7425 3350) $PN BT72
J 0
(-7415 3360);
DISPLAY 0.489362 (-7415 3360);
PAINT MONO (-7415 3360);
FORCEPROP 0 LASTPIN (-7425 3300) $PN BT73
J 0
(-7415 3310);
DISPLAY 0.489362 (-7415 3310);
PAINT MONO (-7415 3310);
FORCEPROP 0 LASTPIN (-7425 3250) $PN BU1
J 0
(-7415 3260);
DISPLAY 0.489362 (-7415 3260);
PAINT MONO (-7415 3260);
FORCEPROP 0 LASTPIN (-7425 3200) $PN BU4
J 0
(-7415 3210);
DISPLAY 0.489362 (-7415 3210);
PAINT MONO (-7415 3210);
FORCEPROP 0 LASTPIN (-7425 3150) $PN BU6
J 0
(-7415 3160);
DISPLAY 0.489362 (-7415 3160);
PAINT MONO (-7415 3160);
FORCEPROP 0 LASTPIN (-7425 3100) $PN BU8
J 0
(-7415 3110);
DISPLAY 0.489362 (-7415 3110);
PAINT MONO (-7415 3110);
FORCEPROP 0 LASTPIN (-7425 3050) $PN BU11
J 0
(-7415 3060);
DISPLAY 0.489362 (-7415 3060);
PAINT MONO (-7415 3060);
FORCEPROP 0 LASTPIN (-7425 3000) $PN BU13
J 0
(-7415 3010);
DISPLAY 0.489362 (-7415 3010);
PAINT MONO (-7415 3010);
FORCEPROP 0 LASTPIN (-7425 2950) $PN BU15
J 0
(-7415 2960);
DISPLAY 0.489362 (-7415 2960);
PAINT MONO (-7415 2960);
FORCEPROP 0 LASTPIN (-7425 2900) $PN BU18
J 0
(-7415 2910);
DISPLAY 0.489362 (-7415 2910);
PAINT MONO (-7415 2910);
FORCEPROP 0 LASTPIN (-7425 2850) $PN BU20
J 0
(-7415 2860);
DISPLAY 0.489362 (-7415 2860);
PAINT MONO (-7415 2860);
FORCEPROP 0 LASTPIN (-7425 2800) $PN BU22
J 0
(-7415 2810);
DISPLAY 0.489362 (-7415 2810);
PAINT MONO (-7415 2810);
FORCEPROP 0 LASTPIN (-7425 2750) $PN BU25
J 0
(-7415 2760);
DISPLAY 0.489362 (-7415 2760);
PAINT MONO (-7415 2760);
FORCEPROP 0 LASTPIN (-7425 2700) $PN BU28
J 0
(-7415 2710);
DISPLAY 0.489362 (-7415 2710);
PAINT MONO (-7415 2710);
FORCEPROP 0 LASTPIN (-7425 2650) $PN BU31
J 0
(-7415 2660);
DISPLAY 0.489362 (-7415 2660);
PAINT MONO (-7415 2660);
FORCEPROP 0 LASTPIN (-7425 2600) $PN BU34
J 0
(-7415 2610);
DISPLAY 0.489362 (-7415 2610);
PAINT MONO (-7415 2610);
FORCEPROP 0 LASTPIN (-7425 2550) $PN BU35
J 0
(-7415 2560);
DISPLAY 0.489362 (-7415 2560);
PAINT MONO (-7415 2560);
FORCEPROP 0 LASTPIN (-7425 2500) $PN BU36
J 0
(-7415 2510);
DISPLAY 0.489362 (-7415 2510);
PAINT MONO (-7415 2510);
FORCEPROP 0 LASTPIN (-7425 2450) $PN BU40
J 0
(-7415 2460);
DISPLAY 0.489362 (-7415 2460);
PAINT MONO (-7415 2460);
FORCEPROP 0 LASTPIN (-7425 2400) $PN BU41
J 0
(-7415 2410);
DISPLAY 0.489362 (-7415 2410);
PAINT MONO (-7415 2410);
FORCEPROP 0 LASTPIN (-7425 2350) $PN BU42
J 0
(-7415 2360);
DISPLAY 0.489362 (-7415 2360);
PAINT MONO (-7415 2360);
FORCEPROP 0 LASTPIN (-7425 2300) $PN BU45
J 0
(-7415 2310);
DISPLAY 0.489362 (-7415 2310);
PAINT MONO (-7415 2310);
FORCEPROP 0 LASTPIN (-7425 2250) $PN BU48
J 0
(-7415 2260);
DISPLAY 0.489362 (-7415 2260);
PAINT MONO (-7415 2260);
FORCEPROP 0 LASTPIN (-7425 2200) $PN BU51
J 0
(-7415 2210);
DISPLAY 0.489362 (-7415 2210);
PAINT MONO (-7415 2210);
FORCEPROP 0 LASTPIN (-7425 2150) $PN BU54
J 0
(-7415 2160);
DISPLAY 0.489362 (-7415 2160);
PAINT MONO (-7415 2160);
FORCEPROP 0 LASTPIN (-7425 2100) $PN BU56
J 0
(-7415 2110);
DISPLAY 0.489362 (-7415 2110);
PAINT MONO (-7415 2110);
FORCEPROP 0 LASTPIN (-7425 2050) $PN BU58
J 0
(-7415 2060);
DISPLAY 0.489362 (-7415 2060);
PAINT MONO (-7415 2060);
FORCEPROP 0 LASTPIN (-7425 2000) $PN BU61
J 0
(-7415 2010);
DISPLAY 0.489362 (-7415 2010);
PAINT MONO (-7415 2010);
FORCEPROP 0 LASTPIN (-7425 1950) $PN BU63
J 0
(-7415 1960);
DISPLAY 0.489362 (-7415 1960);
PAINT MONO (-7415 1960);
FORCEPROP 0 LASTPIN (-7425 1900) $PN BU65
J 0
(-7415 1910);
DISPLAY 0.489362 (-7415 1910);
PAINT MONO (-7415 1910);
FORCEPROP 0 LASTPIN (-7425 1850) $PN BU68
J 0
(-7415 1860);
DISPLAY 0.489362 (-7415 1860);
PAINT MONO (-7415 1860);
FORCEPROP 0 LASTPIN (-7425 1800) $PN BU70
J 0
(-7415 1810);
DISPLAY 0.489362 (-7415 1810);
PAINT MONO (-7415 1810);
FORCEPROP 0 LASTPIN (-7425 1750) $PN BU72
J 0
(-7415 1760);
DISPLAY 0.489362 (-7415 1760);
PAINT MONO (-7415 1760);
FORCEPROP 0 LASTPIN (-7425 1700) $PN BU75
J 0
(-7415 1710);
DISPLAY 0.489362 (-7415 1710);
PAINT MONO (-7415 1710);
FORCEPROP 0 LASTPIN (-7425 1650) $PN BV3
J 0
(-7415 1660);
DISPLAY 0.489362 (-7415 1660);
PAINT MONO (-7415 1660);
FORCEPROP 0 LASTPIN (-7425 1600) $PN BV8
J 0
(-7415 1610);
DISPLAY 0.489362 (-7415 1610);
PAINT MONO (-7415 1610);
FORCEPROP 0 LASTPIN (-7425 1550) $PN BV10
J 0
(-7415 1560);
DISPLAY 0.489362 (-7415 1560);
PAINT MONO (-7415 1560);
FORCEPROP 0 LASTPIN (-7425 1500) $PN BV15
J 0
(-7415 1510);
DISPLAY 0.489362 (-7415 1510);
PAINT MONO (-7415 1510);
FORCEPROP 0 LASTPIN (-7425 1450) $PN BV17
J 0
(-7415 1460);
DISPLAY 0.489362 (-7415 1460);
PAINT MONO (-7415 1460);
FORCEPROP 0 LASTPIN (-7425 1400) $PN BV23
J 0
(-7415 1410);
DISPLAY 0.489362 (-7415 1410);
PAINT MONO (-7415 1410);
FORCEPROP 0 LASTPIN (-7425 1350) $PN BV24
J 0
(-7415 1360);
DISPLAY 0.489362 (-7415 1360);
PAINT MONO (-7415 1360);
FORCEPROP 0 LASTPIN (-7425 1300) $PN BV25
J 0
(-7415 1310);
DISPLAY 0.489362 (-7415 1310);
PAINT MONO (-7415 1310);
FORCEPROP 0 LASTPIN (-7425 1250) $PN BV26
J 0
(-7415 1260);
DISPLAY 0.489362 (-7415 1260);
PAINT MONO (-7415 1260);
FORCEPROP 0 LASTPIN (-7425 1200) $PN BV27
J 0
(-7415 1210);
DISPLAY 0.489362 (-7415 1210);
PAINT MONO (-7415 1210);
FORCEPROP 0 LASTPIN (-7425 1150) $PN BV28
J 0
(-7415 1160);
DISPLAY 0.489362 (-7415 1160);
PAINT MONO (-7415 1160);
FORCEPROP 0 LASTPIN (-7425 1100) $PN BV29
J 0
(-7415 1110);
DISPLAY 0.489362 (-7415 1110);
PAINT MONO (-7415 1110);
FORCEPROP 0 LASTPIN (-7425 1050) $PN BV30
J 0
(-7415 1060);
DISPLAY 0.489362 (-7415 1060);
PAINT MONO (-7415 1060);
FORCEPROP 0 LASTPIN (-7425 1000) $PN BV31
J 0
(-7415 1010);
DISPLAY 0.489362 (-7415 1010);
PAINT MONO (-7415 1010);
FORCEPROP 0 LASTPIN (-7425 950) $PN BV32
J 0
(-7415 960);
DISPLAY 0.489362 (-7415 960);
PAINT MONO (-7415 960);
FORCEPROP 0 LASTPIN (-7425 900) $PN BV33
J 0
(-7415 910);
DISPLAY 0.489362 (-7415 910);
PAINT MONO (-7415 910);
FORCEPROP 0 LASTPIN (-7425 850) $PN BV34
J 0
(-7415 860);
DISPLAY 0.489362 (-7415 860);
PAINT MONO (-7415 860);
FORCEPROP 0 LASTPIN (-7425 800) $PN BV37
J 0
(-7415 810);
DISPLAY 0.489362 (-7415 810);
PAINT MONO (-7415 810);
FORCEPROP 0 LASTPIN (-7425 750) $PN BV39
J 0
(-7415 760);
DISPLAY 0.489362 (-7415 760);
PAINT MONO (-7415 760);
FORCEPROP 0 LASTPIN (-7425 700) $PN BV43
J 0
(-7415 710);
DISPLAY 0.489362 (-7415 710);
PAINT MONO (-7415 710);
FORCEPROP 0 LASTPIN (-7425 650) $PN BV44
J 0
(-7415 660);
DISPLAY 0.489362 (-7415 660);
PAINT MONO (-7415 660);
FORCEPROP 0 LASTPIN (-7425 600) $PN BV45
J 0
(-7415 610);
DISPLAY 0.489362 (-7415 610);
PAINT MONO (-7415 610);
FORCEPROP 2 LAST PART_TYPE SMLF
J 0
(-8600 6700);
DISPLAY 1.021277 (-8600 6700);
FORCEPROP 1 LAST MATERIAL IO
J 0
(-8370 6582);
DISPLAY 0.489362 (-8370 6582);
PAINT SKYBLUE (-8370 6582);
FORCEPROP 2 LAST VALUE SOCKET6096_13568-001
J 0
(-8375 6625);
DISPLAY 0.489362 (-8375 6625);
PAINT SKYBLUE (-8375 6625);
FORCEPROP 2 LAST CDS_LIB pure_quanta
J 0
(-7975 3500);
DISPLAY INVISIBLE (-7975 3500);
FORCEPROP 1 LAST CDS_LMAN_SYM_OUTLINE -400,3050,400,-3050
J 0
(-7975 3500);
DISPLAY 0.468085 (-7975 3500);
PAINT GREEN (-7975 3500);
DISPLAY INVISIBLE (-7975 3500);
FORCEPROP 1 LAST NEEDS_NO_SIZE TRUE
J 0
(-7975 3500);
DISPLAY 0.723404 (-7975 3500);
PAINT GREEN (-7975 3500);
DISPLAY INVISIBLE (-7975 3500);
FORCEPROP 1 LAST PATH I1
J 0
(-7975 3500);
DISPLAY 0.723404 (-7975 3500);
PAINT GREEN (-7975 3500);
DISPLAY INVISIBLE (-7975 3500);
FORCEPROP 1 LAST PART_NUMBER DGA^6000030
J 0
(-8375 6725);
DISPLAY 0.489362 (-8375 6725);
PAINT SKYBLUE (-8375 6725);
DISPLAY INVISIBLE (-8375 6725);
FORCEADD UNIVERSAL_GND..1
(-6675 475);
FORCEPROP 3 LASTPIN (-6675 525) SIG_NAME GND\g
J 0
(-6665 535);
DISPLAY 0.659574 (-6665 535);
PAINT MONO (-6665 535);
DISPLAY INVISIBLE (-6665 535);
FORCEPROP 2 LAST CDS_LIB pure_quanta_power
J 0
(-6675 475);
DISPLAY INVISIBLE (-6675 475);
FORCEPROP 1 LAST HDL_POWER GND
J 1
(-6650 400);
DISPLAY 0.872340 (-6650 400);
PAINT GREEN (-6650 400);
DISPLAY INVISIBLE (-6650 400);
FORCEPROP 1 LAST PATH I10
J 0
(-6600 475);
DISPLAY 0.872340 (-6600 475);
PAINT AQUA (-6600 475);
DISPLAY INVISIBLE (-6600 475);
FORCEADD UNIVERSAL_GND..1
(-7250 475);
FORCEPROP 3 LASTPIN (-7250 525) SIG_NAME GND\g
J 0
(-7240 535);
DISPLAY 0.659574 (-7240 535);
PAINT MONO (-7240 535);
DISPLAY INVISIBLE (-7240 535);
FORCEPROP 2 LAST CDS_LIB pure_quanta_power
J 0
(-7250 475);
DISPLAY INVISIBLE (-7250 475);
FORCEPROP 1 LAST HDL_POWER GND
J 1
(-7225 400);
DISPLAY 0.872340 (-7225 400);
PAINT GREEN (-7225 400);
DISPLAY INVISIBLE (-7225 400);
FORCEPROP 1 LAST PATH I11
J 0
(-7175 475);
DISPLAY 0.872340 (-7175 475);
PAINT AQUA (-7175 475);
DISPLAY INVISIBLE (-7175 475);
FORCEADD UNIVERSAL_GND..1
(-8700 450);
FORCEPROP 3 LASTPIN (-8700 500) SIG_NAME GND\g
J 0
(-8690 510);
DISPLAY 0.659574 (-8690 510);
PAINT MONO (-8690 510);
DISPLAY INVISIBLE (-8690 510);
FORCEPROP 2 LAST CDS_LIB pure_quanta_power
J 0
(-8700 450);
DISPLAY INVISIBLE (-8700 450);
FORCEPROP 1 LAST HDL_POWER GND
J 1
(-8675 375);
DISPLAY 0.872340 (-8675 375);
PAINT GREEN (-8675 375);
DISPLAY INVISIBLE (-8675 375);
FORCEPROP 1 LAST PATH I12
J 0
(-8625 450);
DISPLAY 0.872340 (-8625 450);
PAINT AQUA (-8625 450);
DISPLAY INVISIBLE (-8625 450);
FORCEADD GENOA_SP5..37
(-5950 3500);
FORCEPROP 1 LAST LOCATION U26
J 0
(-6350 6650);
DISPLAY 0.489362 (-6350 6650);
PAINT SKYBLUE (-6350 6650);
FORCEPROP 0 LAST $SEC 37
J 0
(-6325 6900);
DISPLAY 0.680851 (-6325 6900);
PAINT MONO (-6325 6900);
DISPLAY INVISIBLE (-6325 6900);
FORCEPROP 0 LAST CDS_SEC 37
J 0
(-6325 6900);
DISPLAY 1.021277 (-6325 6900);
DISPLAY INVISIBLE (-6325 6900);
FORCEPROP 0 LASTPIN (-6500 6400) $PN BV46
J 2
(-6510 6410);
DISPLAY 0.489362 (-6510 6410);
PAINT MONO (-6510 6410);
FORCEPROP 0 LASTPIN (-6500 6350) $PN BV47
J 2
(-6510 6360);
DISPLAY 0.489362 (-6510 6360);
PAINT MONO (-6510 6360);
FORCEPROP 0 LASTPIN (-6500 6300) $PN BV48
J 2
(-6510 6310);
DISPLAY 0.489362 (-6510 6310);
PAINT MONO (-6510 6310);
FORCEPROP 0 LASTPIN (-6500 6250) $PN BV49
J 2
(-6510 6260);
DISPLAY 0.489362 (-6510 6260);
PAINT MONO (-6510 6260);
FORCEPROP 0 LASTPIN (-6500 6200) $PN BV50
J 2
(-6510 6210);
DISPLAY 0.489362 (-6510 6210);
PAINT MONO (-6510 6210);
FORCEPROP 0 LASTPIN (-6500 6150) $PN BV51
J 2
(-6510 6160);
DISPLAY 0.489362 (-6510 6160);
PAINT MONO (-6510 6160);
FORCEPROP 0 LASTPIN (-6500 6100) $PN BV52
J 2
(-6510 6110);
DISPLAY 0.489362 (-6510 6110);
PAINT MONO (-6510 6110);
FORCEPROP 0 LASTPIN (-6500 6050) $PN BV53
J 2
(-6510 6060);
DISPLAY 0.489362 (-6510 6060);
PAINT MONO (-6510 6060);
FORCEPROP 0 LASTPIN (-6500 6000) $PN BV59
J 2
(-6510 6010);
DISPLAY 0.489362 (-6510 6010);
PAINT MONO (-6510 6010);
FORCEPROP 0 LASTPIN (-6500 5950) $PN BV61
J 2
(-6510 5960);
DISPLAY 0.489362 (-6510 5960);
PAINT MONO (-6510 5960);
FORCEPROP 0 LASTPIN (-6500 5900) $PN BV66
J 2
(-6510 5910);
DISPLAY 0.489362 (-6510 5910);
PAINT MONO (-6510 5910);
FORCEPROP 0 LASTPIN (-6500 5850) $PN BV68
J 2
(-6510 5860);
DISPLAY 0.489362 (-6510 5860);
PAINT MONO (-6510 5860);
FORCEPROP 0 LASTPIN (-6500 5800) $PN BV73
J 2
(-6510 5810);
DISPLAY 0.489362 (-6510 5810);
PAINT MONO (-6510 5810);
FORCEPROP 0 LASTPIN (-6500 5750) $PN BW1
J 2
(-6510 5760);
DISPLAY 0.489362 (-6510 5760);
PAINT MONO (-6510 5760);
FORCEPROP 0 LASTPIN (-6500 5700) $PN BW4
J 2
(-6510 5710);
DISPLAY 0.489362 (-6510 5710);
PAINT MONO (-6510 5710);
FORCEPROP 0 LASTPIN (-6500 5650) $PN BW6
J 2
(-6510 5660);
DISPLAY 0.489362 (-6510 5660);
PAINT MONO (-6510 5660);
FORCEPROP 0 LASTPIN (-6500 5600) $PN BW8
J 2
(-6510 5610);
DISPLAY 0.489362 (-6510 5610);
PAINT MONO (-6510 5610);
FORCEPROP 0 LASTPIN (-6500 5550) $PN BW11
J 2
(-6510 5560);
DISPLAY 0.489362 (-6510 5560);
PAINT MONO (-6510 5560);
FORCEPROP 0 LASTPIN (-6500 5500) $PN BW13
J 2
(-6510 5510);
DISPLAY 0.489362 (-6510 5510);
PAINT MONO (-6510 5510);
FORCEPROP 0 LASTPIN (-6500 5450) $PN BW15
J 2
(-6510 5460);
DISPLAY 0.489362 (-6510 5460);
PAINT MONO (-6510 5460);
FORCEPROP 0 LASTPIN (-6500 5400) $PN BW18
J 2
(-6510 5410);
DISPLAY 0.489362 (-6510 5410);
PAINT MONO (-6510 5410);
FORCEPROP 0 LASTPIN (-6500 5350) $PN BW20
J 2
(-6510 5360);
DISPLAY 0.489362 (-6510 5360);
PAINT MONO (-6510 5360);
FORCEPROP 0 LASTPIN (-6500 5300) $PN BW22
J 2
(-6510 5310);
DISPLAY 0.489362 (-6510 5310);
PAINT MONO (-6510 5310);
FORCEPROP 0 LASTPIN (-6500 5250) $PN BW28
J 2
(-6510 5260);
DISPLAY 0.489362 (-6510 5260);
PAINT MONO (-6510 5260);
FORCEPROP 0 LASTPIN (-6500 5200) $PN BW31
J 2
(-6510 5210);
DISPLAY 0.489362 (-6510 5210);
PAINT MONO (-6510 5210);
FORCEPROP 0 LASTPIN (-6500 5150) $PN BW34
J 2
(-6510 5160);
DISPLAY 0.489362 (-6510 5160);
PAINT MONO (-6510 5160);
FORCEPROP 0 LASTPIN (-6500 5100) $PN BW42
J 2
(-6510 5110);
DISPLAY 0.489362 (-6510 5110);
PAINT MONO (-6510 5110);
FORCEPROP 0 LASTPIN (-6500 5050) $PN BW45
J 2
(-6510 5060);
DISPLAY 0.489362 (-6510 5060);
PAINT MONO (-6510 5060);
FORCEPROP 0 LASTPIN (-6500 5000) $PN BW48
J 2
(-6510 5010);
DISPLAY 0.489362 (-6510 5010);
PAINT MONO (-6510 5010);
FORCEPROP 0 LASTPIN (-6500 4950) $PN BW51
J 2
(-6510 4960);
DISPLAY 0.489362 (-6510 4960);
PAINT MONO (-6510 4960);
FORCEPROP 0 LASTPIN (-6500 4900) $PN BW54
J 2
(-6510 4910);
DISPLAY 0.489362 (-6510 4910);
PAINT MONO (-6510 4910);
FORCEPROP 0 LASTPIN (-6500 4850) $PN BW56
J 2
(-6510 4860);
DISPLAY 0.489362 (-6510 4860);
PAINT MONO (-6510 4860);
FORCEPROP 0 LASTPIN (-6500 4800) $PN BW58
J 2
(-6510 4810);
DISPLAY 0.489362 (-6510 4810);
PAINT MONO (-6510 4810);
FORCEPROP 0 LASTPIN (-6500 4750) $PN BW61
J 2
(-6510 4760);
DISPLAY 0.489362 (-6510 4760);
PAINT MONO (-6510 4760);
FORCEPROP 0 LASTPIN (-6500 4700) $PN BW63
J 2
(-6510 4710);
DISPLAY 0.489362 (-6510 4710);
PAINT MONO (-6510 4710);
FORCEPROP 0 LASTPIN (-6500 4650) $PN BW65
J 2
(-6510 4660);
DISPLAY 0.489362 (-6510 4660);
PAINT MONO (-6510 4660);
FORCEPROP 0 LASTPIN (-6500 4600) $PN BW68
J 2
(-6510 4610);
DISPLAY 0.489362 (-6510 4610);
PAINT MONO (-6510 4610);
FORCEPROP 0 LASTPIN (-6500 4550) $PN BW70
J 2
(-6510 4560);
DISPLAY 0.489362 (-6510 4560);
PAINT MONO (-6510 4560);
FORCEPROP 0 LASTPIN (-6500 4500) $PN BW72
J 2
(-6510 4510);
DISPLAY 0.489362 (-6510 4510);
PAINT MONO (-6510 4510);
FORCEPROP 0 LASTPIN (-6500 4450) $PN BW75
J 2
(-6510 4460);
DISPLAY 0.489362 (-6510 4460);
PAINT MONO (-6510 4460);
FORCEPROP 0 LASTPIN (-6500 4400) $PN BY3
J 2
(-6510 4410);
DISPLAY 0.489362 (-6510 4410);
PAINT MONO (-6510 4410);
FORCEPROP 0 LASTPIN (-6500 4350) $PN BY5
J 2
(-6510 4360);
DISPLAY 0.489362 (-6510 4360);
PAINT MONO (-6510 4360);
FORCEPROP 0 LASTPIN (-6500 4300) $PN BY8
J 2
(-6510 4310);
DISPLAY 0.489362 (-6510 4310);
PAINT MONO (-6510 4310);
FORCEPROP 0 LASTPIN (-6500 4250) $PN BY10
J 2
(-6510 4260);
DISPLAY 0.489362 (-6510 4260);
PAINT MONO (-6510 4260);
FORCEPROP 0 LASTPIN (-6500 4200) $PN BY12
J 2
(-6510 4210);
DISPLAY 0.489362 (-6510 4210);
PAINT MONO (-6510 4210);
FORCEPROP 0 LASTPIN (-6500 4150) $PN BY15
J 2
(-6510 4160);
DISPLAY 0.489362 (-6510 4160);
PAINT MONO (-6510 4160);
FORCEPROP 0 LASTPIN (-6500 4100) $PN BY17
J 2
(-6510 4110);
DISPLAY 0.489362 (-6510 4110);
PAINT MONO (-6510 4110);
FORCEPROP 0 LASTPIN (-6500 4050) $PN BY19
J 2
(-6510 4060);
DISPLAY 0.489362 (-6510 4060);
PAINT MONO (-6510 4060);
FORCEPROP 0 LASTPIN (-6500 4000) $PN BY22
J 2
(-6510 4010);
DISPLAY 0.489362 (-6510 4010);
PAINT MONO (-6510 4010);
FORCEPROP 0 LASTPIN (-6500 3950) $PN BY25
J 2
(-6510 3960);
DISPLAY 0.489362 (-6510 3960);
PAINT MONO (-6510 3960);
FORCEPROP 0 LASTPIN (-6500 3900) $PN BY28
J 2
(-6510 3910);
DISPLAY 0.489362 (-6510 3910);
PAINT MONO (-6510 3910);
FORCEPROP 0 LASTPIN (-6500 3850) $PN BY31
J 2
(-6510 3860);
DISPLAY 0.489362 (-6510 3860);
PAINT MONO (-6510 3860);
FORCEPROP 0 LASTPIN (-6500 3800) $PN BY34
J 2
(-6510 3810);
DISPLAY 0.489362 (-6510 3810);
PAINT MONO (-6510 3810);
FORCEPROP 0 LASTPIN (-6500 3750) $PN BY37
J 2
(-6510 3760);
DISPLAY 0.489362 (-6510 3760);
PAINT MONO (-6510 3760);
FORCEPROP 0 LASTPIN (-6500 3700) $PN BY39
J 2
(-6510 3710);
DISPLAY 0.489362 (-6510 3710);
PAINT MONO (-6510 3710);
FORCEPROP 0 LASTPIN (-6500 3650) $PN BY42
J 2
(-6510 3660);
DISPLAY 0.489362 (-6510 3660);
PAINT MONO (-6510 3660);
FORCEPROP 0 LASTPIN (-6500 3600) $PN BY45
J 2
(-6510 3610);
DISPLAY 0.489362 (-6510 3610);
PAINT MONO (-6510 3610);
FORCEPROP 0 LASTPIN (-6500 3550) $PN BY48
J 2
(-6510 3560);
DISPLAY 0.489362 (-6510 3560);
PAINT MONO (-6510 3560);
FORCEPROP 0 LASTPIN (-6500 3500) $PN BY51
J 2
(-6510 3510);
DISPLAY 0.489362 (-6510 3510);
PAINT MONO (-6510 3510);
FORCEPROP 0 LASTPIN (-6500 3450) $PN BY54
J 2
(-6510 3460);
DISPLAY 0.489362 (-6510 3460);
PAINT MONO (-6510 3460);
FORCEPROP 0 LASTPIN (-6500 3400) $PN BY57
J 2
(-6510 3410);
DISPLAY 0.489362 (-6510 3410);
PAINT MONO (-6510 3410);
FORCEPROP 0 LASTPIN (-6500 3350) $PN BY59
J 2
(-6510 3360);
DISPLAY 0.489362 (-6510 3360);
PAINT MONO (-6510 3360);
FORCEPROP 0 LASTPIN (-6500 3300) $PN BY61
J 2
(-6510 3310);
DISPLAY 0.489362 (-6510 3310);
PAINT MONO (-6510 3310);
FORCEPROP 0 LASTPIN (-6500 3250) $PN BY64
J 2
(-6510 3260);
DISPLAY 0.489362 (-6510 3260);
PAINT MONO (-6510 3260);
FORCEPROP 0 LASTPIN (-6500 3200) $PN BY66
J 2
(-6510 3210);
DISPLAY 0.489362 (-6510 3210);
PAINT MONO (-6510 3210);
FORCEPROP 0 LASTPIN (-6500 3150) $PN BY68
J 2
(-6510 3160);
DISPLAY 0.489362 (-6510 3160);
PAINT MONO (-6510 3160);
FORCEPROP 0 LASTPIN (-6500 3100) $PN BY71
J 2
(-6510 3110);
DISPLAY 0.489362 (-6510 3110);
PAINT MONO (-6510 3110);
FORCEPROP 0 LASTPIN (-6500 3050) $PN BY73
J 2
(-6510 3060);
DISPLAY 0.489362 (-6510 3060);
PAINT MONO (-6510 3060);
FORCEPROP 0 LASTPIN (-6500 3000) $PN CA1
J 2
(-6510 3010);
DISPLAY 0.489362 (-6510 3010);
PAINT MONO (-6510 3010);
FORCEPROP 0 LASTPIN (-6500 2950) $PN CA6
J 2
(-6510 2960);
DISPLAY 0.489362 (-6510 2960);
PAINT MONO (-6510 2960);
FORCEPROP 0 LASTPIN (-6500 2900) $PN CA8
J 2
(-6510 2910);
DISPLAY 0.489362 (-6510 2910);
PAINT MONO (-6510 2910);
FORCEPROP 0 LASTPIN (-6500 2850) $PN CA13
J 2
(-6510 2860);
DISPLAY 0.489362 (-6510 2860);
PAINT MONO (-6510 2860);
FORCEPROP 0 LASTPIN (-6500 2800) $PN CA15
J 2
(-6510 2810);
DISPLAY 0.489362 (-6510 2810);
PAINT MONO (-6510 2810);
FORCEPROP 0 LASTPIN (-6500 2750) $PN CA20
J 2
(-6510 2760);
DISPLAY 0.489362 (-6510 2760);
PAINT MONO (-6510 2760);
FORCEPROP 0 LASTPIN (-6500 2700) $PN CA22
J 2
(-6510 2710);
DISPLAY 0.489362 (-6510 2710);
PAINT MONO (-6510 2710);
FORCEPROP 0 LASTPIN (-6500 2650) $PN CA25
J 2
(-6510 2660);
DISPLAY 0.489362 (-6510 2660);
PAINT MONO (-6510 2660);
FORCEPROP 0 LASTPIN (-6500 2600) $PN CA28
J 2
(-6510 2610);
DISPLAY 0.489362 (-6510 2610);
PAINT MONO (-6510 2610);
FORCEPROP 0 LASTPIN (-6500 2550) $PN CA31
J 2
(-6510 2560);
DISPLAY 0.489362 (-6510 2560);
PAINT MONO (-6510 2560);
FORCEPROP 0 LASTPIN (-6500 2500) $PN CA34
J 2
(-6510 2510);
DISPLAY 0.489362 (-6510 2510);
PAINT MONO (-6510 2510);
FORCEPROP 0 LASTPIN (-6500 2450) $PN CA35
J 2
(-6510 2460);
DISPLAY 0.489362 (-6510 2460);
PAINT MONO (-6510 2460);
FORCEPROP 0 LASTPIN (-6500 2400) $PN CA36
J 2
(-6510 2410);
DISPLAY 0.489362 (-6510 2410);
PAINT MONO (-6510 2410);
FORCEPROP 0 LASTPIN (-6500 2350) $PN CA40
J 2
(-6510 2360);
DISPLAY 0.489362 (-6510 2360);
PAINT MONO (-6510 2360);
FORCEPROP 0 LASTPIN (-6500 2300) $PN CA41
J 2
(-6510 2310);
DISPLAY 0.489362 (-6510 2310);
PAINT MONO (-6510 2310);
FORCEPROP 0 LASTPIN (-6500 2250) $PN CA42
J 2
(-6510 2260);
DISPLAY 0.489362 (-6510 2260);
PAINT MONO (-6510 2260);
FORCEPROP 0 LASTPIN (-6500 2200) $PN CA45
J 2
(-6510 2210);
DISPLAY 0.489362 (-6510 2210);
PAINT MONO (-6510 2210);
FORCEPROP 0 LASTPIN (-6500 2150) $PN CA48
J 2
(-6510 2160);
DISPLAY 0.489362 (-6510 2160);
PAINT MONO (-6510 2160);
FORCEPROP 0 LASTPIN (-6500 2100) $PN CA51
J 2
(-6510 2110);
DISPLAY 0.489362 (-6510 2110);
PAINT MONO (-6510 2110);
FORCEPROP 0 LASTPIN (-6500 2050) $PN CA54
J 2
(-6510 2060);
DISPLAY 0.489362 (-6510 2060);
PAINT MONO (-6510 2060);
FORCEPROP 0 LASTPIN (-6500 2000) $PN CA56
J 2
(-6510 2010);
DISPLAY 0.489362 (-6510 2010);
PAINT MONO (-6510 2010);
FORCEPROP 0 LASTPIN (-6500 1950) $PN CA61
J 2
(-6510 1960);
DISPLAY 0.489362 (-6510 1960);
PAINT MONO (-6510 1960);
FORCEPROP 0 LASTPIN (-6500 1900) $PN CA63
J 2
(-6510 1910);
DISPLAY 0.489362 (-6510 1910);
PAINT MONO (-6510 1910);
FORCEPROP 0 LASTPIN (-6500 1850) $PN CA68
J 2
(-6510 1860);
DISPLAY 0.489362 (-6510 1860);
PAINT MONO (-6510 1860);
FORCEPROP 0 LASTPIN (-6500 1800) $PN CA70
J 2
(-6510 1810);
DISPLAY 0.489362 (-6510 1810);
PAINT MONO (-6510 1810);
FORCEPROP 0 LASTPIN (-6500 1750) $PN CA75
J 2
(-6510 1760);
DISPLAY 0.489362 (-6510 1760);
PAINT MONO (-6510 1760);
FORCEPROP 0 LASTPIN (-6500 1700) $PN CB3
J 2
(-6510 1710);
DISPLAY 0.489362 (-6510 1710);
PAINT MONO (-6510 1710);
FORCEPROP 0 LASTPIN (-6500 1650) $PN CB5
J 2
(-6510 1660);
DISPLAY 0.489362 (-6510 1660);
PAINT MONO (-6510 1660);
FORCEPROP 0 LASTPIN (-6500 1600) $PN CB8
J 2
(-6510 1610);
DISPLAY 0.489362 (-6510 1610);
PAINT MONO (-6510 1610);
FORCEPROP 0 LASTPIN (-6500 1550) $PN CB10
J 2
(-6510 1560);
DISPLAY 0.489362 (-6510 1560);
PAINT MONO (-6510 1560);
FORCEPROP 0 LASTPIN (-6500 1500) $PN CB12
J 2
(-6510 1510);
DISPLAY 0.489362 (-6510 1510);
PAINT MONO (-6510 1510);
FORCEPROP 0 LASTPIN (-6500 1450) $PN CB15
J 2
(-6510 1460);
DISPLAY 0.489362 (-6510 1460);
PAINT MONO (-6510 1460);
FORCEPROP 0 LASTPIN (-6500 1400) $PN CB17
J 2
(-6510 1410);
DISPLAY 0.489362 (-6510 1410);
PAINT MONO (-6510 1410);
FORCEPROP 0 LASTPIN (-6500 1350) $PN CB19
J 2
(-6510 1360);
DISPLAY 0.489362 (-6510 1360);
PAINT MONO (-6510 1360);
FORCEPROP 0 LASTPIN (-6500 1300) $PN CB23
J 2
(-6510 1310);
DISPLAY 0.489362 (-6510 1310);
PAINT MONO (-6510 1310);
FORCEPROP 0 LASTPIN (-6500 1250) $PN CB24
J 2
(-6510 1260);
DISPLAY 0.489362 (-6510 1260);
PAINT MONO (-6510 1260);
FORCEPROP 0 LASTPIN (-6500 1200) $PN CB25
J 2
(-6510 1210);
DISPLAY 0.489362 (-6510 1210);
PAINT MONO (-6510 1210);
FORCEPROP 0 LASTPIN (-6500 1150) $PN CB26
J 2
(-6510 1160);
DISPLAY 0.489362 (-6510 1160);
PAINT MONO (-6510 1160);
FORCEPROP 0 LASTPIN (-6500 1100) $PN CB27
J 2
(-6510 1110);
DISPLAY 0.489362 (-6510 1110);
PAINT MONO (-6510 1110);
FORCEPROP 0 LASTPIN (-6500 1050) $PN CB28
J 2
(-6510 1060);
DISPLAY 0.489362 (-6510 1060);
PAINT MONO (-6510 1060);
FORCEPROP 0 LASTPIN (-6500 1000) $PN CB29
J 2
(-6510 1010);
DISPLAY 0.489362 (-6510 1010);
PAINT MONO (-6510 1010);
FORCEPROP 0 LASTPIN (-6500 950) $PN CB30
J 2
(-6510 960);
DISPLAY 0.489362 (-6510 960);
PAINT MONO (-6510 960);
FORCEPROP 0 LASTPIN (-6500 900) $PN CB31
J 2
(-6510 910);
DISPLAY 0.489362 (-6510 910);
PAINT MONO (-6510 910);
FORCEPROP 0 LASTPIN (-6500 850) $PN CB32
J 2
(-6510 860);
DISPLAY 0.489362 (-6510 860);
PAINT MONO (-6510 860);
FORCEPROP 0 LASTPIN (-6500 800) $PN CB33
J 2
(-6510 810);
DISPLAY 0.489362 (-6510 810);
PAINT MONO (-6510 810);
FORCEPROP 0 LASTPIN (-6500 750) $PN CB34
J 2
(-6510 760);
DISPLAY 0.489362 (-6510 760);
PAINT MONO (-6510 760);
FORCEPROP 0 LASTPIN (-6500 700) $PN CB37
J 2
(-6510 710);
DISPLAY 0.489362 (-6510 710);
PAINT MONO (-6510 710);
FORCEPROP 0 LASTPIN (-6500 650) $PN CB39
J 2
(-6510 660);
DISPLAY 0.489362 (-6510 660);
PAINT MONO (-6510 660);
FORCEPROP 0 LASTPIN (-6500 600) $PN CB42
J 2
(-6510 610);
DISPLAY 0.489362 (-6510 610);
PAINT MONO (-6510 610);
FORCEPROP 0 LASTPIN (-6500 550) $PN CB43
J 2
(-6510 560);
DISPLAY 0.489362 (-6510 560);
PAINT MONO (-6510 560);
FORCEPROP 0 LASTPIN (-5400 6350) $PN CB45
J 0
(-5390 6360);
DISPLAY 0.489362 (-5390 6360);
PAINT MONO (-5390 6360);
FORCEPROP 0 LASTPIN (-5400 6300) $PN CB46
J 0
(-5390 6310);
DISPLAY 0.489362 (-5390 6310);
PAINT MONO (-5390 6310);
FORCEPROP 0 LASTPIN (-5400 6250) $PN CB47
J 0
(-5390 6260);
DISPLAY 0.489362 (-5390 6260);
PAINT MONO (-5390 6260);
FORCEPROP 0 LASTPIN (-5400 6200) $PN CB48
J 0
(-5390 6210);
DISPLAY 0.489362 (-5390 6210);
PAINT MONO (-5390 6210);
FORCEPROP 0 LASTPIN (-5400 6150) $PN CB49
J 0
(-5390 6160);
DISPLAY 0.489362 (-5390 6160);
PAINT MONO (-5390 6160);
FORCEPROP 0 LASTPIN (-5400 6100) $PN CB50
J 0
(-5390 6110);
DISPLAY 0.489362 (-5390 6110);
PAINT MONO (-5390 6110);
FORCEPROP 0 LASTPIN (-5400 6050) $PN CB51
J 0
(-5390 6060);
DISPLAY 0.489362 (-5390 6060);
PAINT MONO (-5390 6060);
FORCEPROP 0 LASTPIN (-5400 6000) $PN CB52
J 0
(-5390 6010);
DISPLAY 0.489362 (-5390 6010);
PAINT MONO (-5390 6010);
FORCEPROP 0 LASTPIN (-5400 5950) $PN CB53
J 0
(-5390 5960);
DISPLAY 0.489362 (-5390 5960);
PAINT MONO (-5390 5960);
FORCEPROP 0 LASTPIN (-5400 5900) $PN CB57
J 0
(-5390 5910);
DISPLAY 0.489362 (-5390 5910);
PAINT MONO (-5390 5910);
FORCEPROP 0 LASTPIN (-5400 5850) $PN CB59
J 0
(-5390 5860);
DISPLAY 0.489362 (-5390 5860);
PAINT MONO (-5390 5860);
FORCEPROP 0 LASTPIN (-5400 5800) $PN CB61
J 0
(-5390 5810);
DISPLAY 0.489362 (-5390 5810);
PAINT MONO (-5390 5810);
FORCEPROP 0 LASTPIN (-5400 5750) $PN CB64
J 0
(-5390 5760);
DISPLAY 0.489362 (-5390 5760);
PAINT MONO (-5390 5760);
FORCEPROP 0 LASTPIN (-5400 5700) $PN CB66
J 0
(-5390 5710);
DISPLAY 0.489362 (-5390 5710);
PAINT MONO (-5390 5710);
FORCEPROP 0 LASTPIN (-5400 5650) $PN CB68
J 0
(-5390 5660);
DISPLAY 0.489362 (-5390 5660);
PAINT MONO (-5390 5660);
FORCEPROP 0 LASTPIN (-5400 5600) $PN CB71
J 0
(-5390 5610);
DISPLAY 0.489362 (-5390 5610);
PAINT MONO (-5390 5610);
FORCEPROP 0 LASTPIN (-5400 5550) $PN CB73
J 0
(-5390 5560);
DISPLAY 0.489362 (-5390 5560);
PAINT MONO (-5390 5560);
FORCEPROP 0 LASTPIN (-5400 5500) $PN CC1
J 0
(-5390 5510);
DISPLAY 0.489362 (-5390 5510);
PAINT MONO (-5390 5510);
FORCEPROP 0 LASTPIN (-5400 5450) $PN CC4
J 0
(-5390 5460);
DISPLAY 0.489362 (-5390 5460);
PAINT MONO (-5390 5460);
FORCEPROP 0 LASTPIN (-5400 5400) $PN CC6
J 0
(-5390 5410);
DISPLAY 0.489362 (-5390 5410);
PAINT MONO (-5390 5410);
FORCEPROP 0 LASTPIN (-5400 5350) $PN CC8
J 0
(-5390 5360);
DISPLAY 0.489362 (-5390 5360);
PAINT MONO (-5390 5360);
FORCEPROP 0 LASTPIN (-5400 5300) $PN CC11
J 0
(-5390 5310);
DISPLAY 0.489362 (-5390 5310);
PAINT MONO (-5390 5310);
FORCEPROP 0 LASTPIN (-5400 5250) $PN CC13
J 0
(-5390 5260);
DISPLAY 0.489362 (-5390 5260);
PAINT MONO (-5390 5260);
FORCEPROP 0 LASTPIN (-5400 5200) $PN CC15
J 0
(-5390 5210);
DISPLAY 0.489362 (-5390 5210);
PAINT MONO (-5390 5210);
FORCEPROP 0 LASTPIN (-5400 5150) $PN CC18
J 0
(-5390 5160);
DISPLAY 0.489362 (-5390 5160);
PAINT MONO (-5390 5160);
FORCEPROP 0 LASTPIN (-5400 5100) $PN CC20
J 0
(-5390 5110);
DISPLAY 0.489362 (-5390 5110);
PAINT MONO (-5390 5110);
FORCEPROP 0 LASTPIN (-5400 5050) $PN CC25
J 0
(-5390 5060);
DISPLAY 0.489362 (-5390 5060);
PAINT MONO (-5390 5060);
FORCEPROP 0 LASTPIN (-5400 5000) $PN CC28
J 0
(-5390 5010);
DISPLAY 0.489362 (-5390 5010);
PAINT MONO (-5390 5010);
FORCEPROP 0 LASTPIN (-5400 4950) $PN CC31
J 0
(-5390 4960);
DISPLAY 0.489362 (-5390 4960);
PAINT MONO (-5390 4960);
FORCEPROP 0 LASTPIN (-5400 4900) $PN CC34
J 0
(-5390 4910);
DISPLAY 0.489362 (-5390 4910);
PAINT MONO (-5390 4910);
FORCEPROP 0 LASTPIN (-5400 4850) $PN CC42
J 0
(-5390 4860);
DISPLAY 0.489362 (-5390 4860);
PAINT MONO (-5390 4860);
FORCEPROP 0 LASTPIN (-5400 4800) $PN CC45
J 0
(-5390 4810);
DISPLAY 0.489362 (-5390 4810);
PAINT MONO (-5390 4810);
FORCEPROP 0 LASTPIN (-5400 4750) $PN CC48
J 0
(-5390 4760);
DISPLAY 0.489362 (-5390 4760);
PAINT MONO (-5390 4760);
FORCEPROP 0 LASTPIN (-5400 4700) $PN CC51
J 0
(-5390 4710);
DISPLAY 0.489362 (-5390 4710);
PAINT MONO (-5390 4710);
FORCEPROP 0 LASTPIN (-5400 4650) $PN CC54
J 0
(-5390 4660);
DISPLAY 0.489362 (-5390 4660);
PAINT MONO (-5390 4660);
FORCEPROP 0 LASTPIN (-5400 4600) $PN CC56
J 0
(-5390 4610);
DISPLAY 0.489362 (-5390 4610);
PAINT MONO (-5390 4610);
FORCEPROP 0 LASTPIN (-5400 4550) $PN CC58
J 0
(-5390 4560);
DISPLAY 0.489362 (-5390 4560);
PAINT MONO (-5390 4560);
FORCEPROP 0 LASTPIN (-5400 4500) $PN CC61
J 0
(-5390 4510);
DISPLAY 0.489362 (-5390 4510);
PAINT MONO (-5390 4510);
FORCEPROP 0 LASTPIN (-5400 4450) $PN CC63
J 0
(-5390 4460);
DISPLAY 0.489362 (-5390 4460);
PAINT MONO (-5390 4460);
FORCEPROP 0 LASTPIN (-5400 4400) $PN CC65
J 0
(-5390 4410);
DISPLAY 0.489362 (-5390 4410);
PAINT MONO (-5390 4410);
FORCEPROP 0 LASTPIN (-5400 4350) $PN CC68
J 0
(-5390 4360);
DISPLAY 0.489362 (-5390 4360);
PAINT MONO (-5390 4360);
FORCEPROP 0 LASTPIN (-5400 4300) $PN CC70
J 0
(-5390 4310);
DISPLAY 0.489362 (-5390 4310);
PAINT MONO (-5390 4310);
FORCEPROP 0 LASTPIN (-5400 4250) $PN CC72
J 0
(-5390 4260);
DISPLAY 0.489362 (-5390 4260);
PAINT MONO (-5390 4260);
FORCEPROP 0 LASTPIN (-5400 4200) $PN CC75
J 0
(-5390 4210);
DISPLAY 0.489362 (-5390 4210);
PAINT MONO (-5390 4210);
FORCEPROP 0 LASTPIN (-5400 4150) $PN CD3
J 0
(-5390 4160);
DISPLAY 0.489362 (-5390 4160);
PAINT MONO (-5390 4160);
FORCEPROP 0 LASTPIN (-5400 4100) $PN CD8
J 0
(-5390 4110);
DISPLAY 0.489362 (-5390 4110);
PAINT MONO (-5390 4110);
FORCEPROP 0 LASTPIN (-5400 4050) $PN CD10
J 0
(-5390 4060);
DISPLAY 0.489362 (-5390 4060);
PAINT MONO (-5390 4060);
FORCEPROP 0 LASTPIN (-5400 4000) $PN CD15
J 0
(-5390 4010);
DISPLAY 0.489362 (-5390 4010);
PAINT MONO (-5390 4010);
FORCEPROP 0 LASTPIN (-5400 3950) $PN CD17
J 0
(-5390 3960);
DISPLAY 0.489362 (-5390 3960);
PAINT MONO (-5390 3960);
FORCEPROP 0 LASTPIN (-5400 3900) $PN CD22
J 0
(-5390 3910);
DISPLAY 0.489362 (-5390 3910);
PAINT MONO (-5390 3910);
FORCEPROP 0 LASTPIN (-5400 3850) $PN CD25
J 0
(-5390 3860);
DISPLAY 0.489362 (-5390 3860);
PAINT MONO (-5390 3860);
FORCEPROP 0 LASTPIN (-5400 3800) $PN CD28
J 0
(-5390 3810);
DISPLAY 0.489362 (-5390 3810);
PAINT MONO (-5390 3810);
FORCEPROP 0 LASTPIN (-5400 3750) $PN CD31
J 0
(-5390 3760);
DISPLAY 0.489362 (-5390 3760);
PAINT MONO (-5390 3760);
FORCEPROP 0 LASTPIN (-5400 3700) $PN CD34
J 0
(-5390 3710);
DISPLAY 0.489362 (-5390 3710);
PAINT MONO (-5390 3710);
FORCEPROP 0 LASTPIN (-5400 3650) $PN CD37
J 0
(-5390 3660);
DISPLAY 0.489362 (-5390 3660);
PAINT MONO (-5390 3660);
FORCEPROP 0 LASTPIN (-5400 3600) $PN CD39
J 0
(-5390 3610);
DISPLAY 0.489362 (-5390 3610);
PAINT MONO (-5390 3610);
FORCEPROP 0 LASTPIN (-5400 3550) $PN CD42
J 0
(-5390 3560);
DISPLAY 0.489362 (-5390 3560);
PAINT MONO (-5390 3560);
FORCEPROP 0 LASTPIN (-5400 3500) $PN CD45
J 0
(-5390 3510);
DISPLAY 0.489362 (-5390 3510);
PAINT MONO (-5390 3510);
FORCEPROP 0 LASTPIN (-5400 3450) $PN CD48
J 0
(-5390 3460);
DISPLAY 0.489362 (-5390 3460);
PAINT MONO (-5390 3460);
FORCEPROP 0 LASTPIN (-5400 3400) $PN CD51
J 0
(-5390 3410);
DISPLAY 0.489362 (-5390 3410);
PAINT MONO (-5390 3410);
FORCEPROP 0 LASTPIN (-5400 3350) $PN CD54
J 0
(-5390 3360);
DISPLAY 0.489362 (-5390 3360);
PAINT MONO (-5390 3360);
FORCEPROP 0 LASTPIN (-5400 3300) $PN CD59
J 0
(-5390 3310);
DISPLAY 0.489362 (-5390 3310);
PAINT MONO (-5390 3310);
FORCEPROP 0 LASTPIN (-5400 3250) $PN CD61
J 0
(-5390 3260);
DISPLAY 0.489362 (-5390 3260);
PAINT MONO (-5390 3260);
FORCEPROP 0 LASTPIN (-5400 3200) $PN CD66
J 0
(-5390 3210);
DISPLAY 0.489362 (-5390 3210);
PAINT MONO (-5390 3210);
FORCEPROP 0 LASTPIN (-5400 3150) $PN CD68
J 0
(-5390 3160);
DISPLAY 0.489362 (-5390 3160);
PAINT MONO (-5390 3160);
FORCEPROP 0 LASTPIN (-5400 3100) $PN CD73
J 0
(-5390 3110);
DISPLAY 0.489362 (-5390 3110);
PAINT MONO (-5390 3110);
FORCEPROP 0 LASTPIN (-5400 3050) $PN CE1
J 0
(-5390 3060);
DISPLAY 0.489362 (-5390 3060);
PAINT MONO (-5390 3060);
FORCEPROP 0 LASTPIN (-5400 3000) $PN CE4
J 0
(-5390 3010);
DISPLAY 0.489362 (-5390 3010);
PAINT MONO (-5390 3010);
FORCEPROP 0 LASTPIN (-5400 2950) $PN CE6
J 0
(-5390 2960);
DISPLAY 0.489362 (-5390 2960);
PAINT MONO (-5390 2960);
FORCEPROP 0 LASTPIN (-5400 2900) $PN CE8
J 0
(-5390 2910);
DISPLAY 0.489362 (-5390 2910);
PAINT MONO (-5390 2910);
FORCEPROP 0 LASTPIN (-5400 2850) $PN CE11
J 0
(-5390 2860);
DISPLAY 0.489362 (-5390 2860);
PAINT MONO (-5390 2860);
FORCEPROP 0 LASTPIN (-5400 2800) $PN CE13
J 0
(-5390 2810);
DISPLAY 0.489362 (-5390 2810);
PAINT MONO (-5390 2810);
FORCEPROP 0 LASTPIN (-5400 2750) $PN CE15
J 0
(-5390 2760);
DISPLAY 0.489362 (-5390 2760);
PAINT MONO (-5390 2760);
FORCEPROP 0 LASTPIN (-5400 2700) $PN CE18
J 0
(-5390 2710);
DISPLAY 0.489362 (-5390 2710);
PAINT MONO (-5390 2710);
FORCEPROP 0 LASTPIN (-5400 2650) $PN CE20
J 0
(-5390 2660);
DISPLAY 0.489362 (-5390 2660);
PAINT MONO (-5390 2660);
FORCEPROP 0 LASTPIN (-5400 2600) $PN CE22
J 0
(-5390 2610);
DISPLAY 0.489362 (-5390 2610);
PAINT MONO (-5390 2610);
FORCEPROP 0 LASTPIN (-5400 2550) $PN CE25
J 0
(-5390 2560);
DISPLAY 0.489362 (-5390 2560);
PAINT MONO (-5390 2560);
FORCEPROP 0 LASTPIN (-5400 2500) $PN CE28
J 0
(-5390 2510);
DISPLAY 0.489362 (-5390 2510);
PAINT MONO (-5390 2510);
FORCEPROP 0 LASTPIN (-5400 2450) $PN CE31
J 0
(-5390 2460);
DISPLAY 0.489362 (-5390 2460);
PAINT MONO (-5390 2460);
FORCEPROP 0 LASTPIN (-5400 2400) $PN CE34
J 0
(-5390 2410);
DISPLAY 0.489362 (-5390 2410);
PAINT MONO (-5390 2410);
FORCEPROP 0 LASTPIN (-5400 2350) $PN CE35
J 0
(-5390 2360);
DISPLAY 0.489362 (-5390 2360);
PAINT MONO (-5390 2360);
FORCEPROP 0 LASTPIN (-5400 2300) $PN CE36
J 0
(-5390 2310);
DISPLAY 0.489362 (-5390 2310);
PAINT MONO (-5390 2310);
FORCEPROP 0 LASTPIN (-5400 2250) $PN CE40
J 0
(-5390 2260);
DISPLAY 0.489362 (-5390 2260);
PAINT MONO (-5390 2260);
FORCEPROP 0 LASTPIN (-5400 2200) $PN CE41
J 0
(-5390 2210);
DISPLAY 0.489362 (-5390 2210);
PAINT MONO (-5390 2210);
FORCEPROP 0 LASTPIN (-5400 2150) $PN CE42
J 0
(-5390 2160);
DISPLAY 0.489362 (-5390 2160);
PAINT MONO (-5390 2160);
FORCEPROP 0 LASTPIN (-5400 2100) $PN CE45
J 0
(-5390 2110);
DISPLAY 0.489362 (-5390 2110);
PAINT MONO (-5390 2110);
FORCEPROP 0 LASTPIN (-5400 2050) $PN CE48
J 0
(-5390 2060);
DISPLAY 0.489362 (-5390 2060);
PAINT MONO (-5390 2060);
FORCEPROP 0 LASTPIN (-5400 2000) $PN CE51
J 0
(-5390 2010);
DISPLAY 0.489362 (-5390 2010);
PAINT MONO (-5390 2010);
FORCEPROP 0 LASTPIN (-5400 1950) $PN CE54
J 0
(-5390 1960);
DISPLAY 0.489362 (-5390 1960);
PAINT MONO (-5390 1960);
FORCEPROP 0 LASTPIN (-5400 1900) $PN CE56
J 0
(-5390 1910);
DISPLAY 0.489362 (-5390 1910);
PAINT MONO (-5390 1910);
FORCEPROP 0 LASTPIN (-5400 1850) $PN CE58
J 0
(-5390 1860);
DISPLAY 0.489362 (-5390 1860);
PAINT MONO (-5390 1860);
FORCEPROP 0 LASTPIN (-5400 1800) $PN CE61
J 0
(-5390 1810);
DISPLAY 0.489362 (-5390 1810);
PAINT MONO (-5390 1810);
FORCEPROP 0 LASTPIN (-5400 1750) $PN CE63
J 0
(-5390 1760);
DISPLAY 0.489362 (-5390 1760);
PAINT MONO (-5390 1760);
FORCEPROP 0 LASTPIN (-5400 1700) $PN CE65
J 0
(-5390 1710);
DISPLAY 0.489362 (-5390 1710);
PAINT MONO (-5390 1710);
FORCEPROP 0 LASTPIN (-5400 1650) $PN CE68
J 0
(-5390 1660);
DISPLAY 0.489362 (-5390 1660);
PAINT MONO (-5390 1660);
FORCEPROP 0 LASTPIN (-5400 1600) $PN CE70
J 0
(-5390 1610);
DISPLAY 0.489362 (-5390 1610);
PAINT MONO (-5390 1610);
FORCEPROP 0 LASTPIN (-5400 1550) $PN CE72
J 0
(-5390 1560);
DISPLAY 0.489362 (-5390 1560);
PAINT MONO (-5390 1560);
FORCEPROP 0 LASTPIN (-5400 1500) $PN CE75
J 0
(-5390 1510);
DISPLAY 0.489362 (-5390 1510);
PAINT MONO (-5390 1510);
FORCEPROP 0 LASTPIN (-5400 1450) $PN CF3
J 0
(-5390 1460);
DISPLAY 0.489362 (-5390 1460);
PAINT MONO (-5390 1460);
FORCEPROP 0 LASTPIN (-5400 1400) $PN CF5
J 0
(-5390 1410);
DISPLAY 0.489362 (-5390 1410);
PAINT MONO (-5390 1410);
FORCEPROP 0 LASTPIN (-5400 1350) $PN CF8
J 0
(-5390 1360);
DISPLAY 0.489362 (-5390 1360);
PAINT MONO (-5390 1360);
FORCEPROP 0 LASTPIN (-5400 1300) $PN CF10
J 0
(-5390 1310);
DISPLAY 0.489362 (-5390 1310);
PAINT MONO (-5390 1310);
FORCEPROP 0 LASTPIN (-5400 1250) $PN CF12
J 0
(-5390 1260);
DISPLAY 0.489362 (-5390 1260);
PAINT MONO (-5390 1260);
FORCEPROP 0 LASTPIN (-5400 1200) $PN CF15
J 0
(-5390 1210);
DISPLAY 0.489362 (-5390 1210);
PAINT MONO (-5390 1210);
FORCEPROP 0 LASTPIN (-5400 1150) $PN CF17
J 0
(-5390 1160);
DISPLAY 0.489362 (-5390 1160);
PAINT MONO (-5390 1160);
FORCEPROP 0 LASTPIN (-5400 1100) $PN CF19
J 0
(-5390 1110);
DISPLAY 0.489362 (-5390 1110);
PAINT MONO (-5390 1110);
FORCEPROP 0 LASTPIN (-5400 1050) $PN CF23
J 0
(-5390 1060);
DISPLAY 0.489362 (-5390 1060);
PAINT MONO (-5390 1060);
FORCEPROP 0 LASTPIN (-5400 1000) $PN CF24
J 0
(-5390 1010);
DISPLAY 0.489362 (-5390 1010);
PAINT MONO (-5390 1010);
FORCEPROP 0 LASTPIN (-5400 950) $PN CF25
J 0
(-5390 960);
DISPLAY 0.489362 (-5390 960);
PAINT MONO (-5390 960);
FORCEPROP 0 LASTPIN (-5400 900) $PN CF26
J 0
(-5390 910);
DISPLAY 0.489362 (-5390 910);
PAINT MONO (-5390 910);
FORCEPROP 0 LASTPIN (-5400 850) $PN CF27
J 0
(-5390 860);
DISPLAY 0.489362 (-5390 860);
PAINT MONO (-5390 860);
FORCEPROP 0 LASTPIN (-5400 800) $PN CF28
J 0
(-5390 810);
DISPLAY 0.489362 (-5390 810);
PAINT MONO (-5390 810);
FORCEPROP 0 LASTPIN (-5400 750) $PN CF29
J 0
(-5390 760);
DISPLAY 0.489362 (-5390 760);
PAINT MONO (-5390 760);
FORCEPROP 0 LASTPIN (-5400 700) $PN CF30
J 0
(-5390 710);
DISPLAY 0.489362 (-5390 710);
PAINT MONO (-5390 710);
FORCEPROP 0 LASTPIN (-5400 650) $PN CF31
J 0
(-5390 660);
DISPLAY 0.489362 (-5390 660);
PAINT MONO (-5390 660);
FORCEPROP 0 LASTPIN (-5400 600) $PN CF32
J 0
(-5390 610);
DISPLAY 0.489362 (-5390 610);
PAINT MONO (-5390 610);
FORCEPROP 0 LASTPIN (-5400 550) $PN CF33
J 0
(-5390 560);
DISPLAY 0.489362 (-5390 560);
PAINT MONO (-5390 560);
FORCEPROP 2 LAST PART_TYPE SMLF
J 0
(-6550 6700);
DISPLAY 1.021277 (-6550 6700);
FORCEPROP 1 LAST MATERIAL IO
J 0
(-6345 6582);
DISPLAY 0.489362 (-6345 6582);
PAINT SKYBLUE (-6345 6582);
FORCEPROP 2 LAST VALUE SOCKET6096_13568-001
J 0
(-6350 6625);
DISPLAY 0.489362 (-6350 6625);
PAINT SKYBLUE (-6350 6625);
FORCEPROP 2 LAST CDS_LIB pure_quanta
J 0
(-5950 3500);
DISPLAY INVISIBLE (-5950 3500);
FORCEPROP 1 LAST CDS_LMAN_SYM_OUTLINE -400,3050,400,-3050
J 0
(-5950 3500);
DISPLAY 0.468085 (-5950 3500);
PAINT GREEN (-5950 3500);
DISPLAY INVISIBLE (-5950 3500);
FORCEPROP 1 LAST NEEDS_NO_SIZE TRUE
J 0
(-5950 3500);
DISPLAY 0.723404 (-5950 3500);
PAINT GREEN (-5950 3500);
DISPLAY INVISIBLE (-5950 3500);
FORCEPROP 1 LAST PATH I2
J 0
(-5950 3500);
DISPLAY 0.723404 (-5950 3500);
PAINT GREEN (-5950 3500);
DISPLAY INVISIBLE (-5950 3500);
FORCEPROP 1 LAST PART_NUMBER DGA^6000030
J 0
(-6345 6709);
DISPLAY 0.489362 (-6345 6709);
PAINT SKYBLUE (-6345 6709);
DISPLAY INVISIBLE (-6345 6709);
FORCEADD GENOA_SP5..38
(-3875 3475);
FORCEPROP 1 LAST LOCATION U26
J 0
(-4275 6650);
DISPLAY 0.489362 (-4275 6650);
PAINT SKYBLUE (-4275 6650);
FORCEPROP 0 LAST $SEC 38
J 0
(-4250 6875);
DISPLAY 0.680851 (-4250 6875);
PAINT MONO (-4250 6875);
DISPLAY INVISIBLE (-4250 6875);
FORCEPROP 0 LAST CDS_SEC 38
J 0
(-4250 6875);
DISPLAY 1.021277 (-4250 6875);
DISPLAY INVISIBLE (-4250 6875);
FORCEPROP 0 LASTPIN (-4425 6325) $PN CF34
J 2
(-4435 6335);
DISPLAY 0.489362 (-4435 6335);
PAINT MONO (-4435 6335);
FORCEPROP 0 LASTPIN (-4425 6275) $PN CF37
J 2
(-4435 6285);
DISPLAY 0.489362 (-4435 6285);
PAINT MONO (-4435 6285);
FORCEPROP 0 LASTPIN (-4425 6225) $PN CF39
J 2
(-4435 6235);
DISPLAY 0.489362 (-4435 6235);
PAINT MONO (-4435 6235);
FORCEPROP 0 LASTPIN (-4425 6175) $PN CF42
J 2
(-4435 6185);
DISPLAY 0.489362 (-4435 6185);
PAINT MONO (-4435 6185);
FORCEPROP 0 LASTPIN (-4425 6125) $PN CF43
J 2
(-4435 6135);
DISPLAY 0.489362 (-4435 6135);
PAINT MONO (-4435 6135);
FORCEPROP 0 LASTPIN (-4425 6075) $PN CF44
J 2
(-4435 6085);
DISPLAY 0.489362 (-4435 6085);
PAINT MONO (-4435 6085);
FORCEPROP 0 LASTPIN (-4425 6025) $PN CF45
J 2
(-4435 6035);
DISPLAY 0.489362 (-4435 6035);
PAINT MONO (-4435 6035);
FORCEPROP 0 LASTPIN (-4425 5975) $PN CF47
J 2
(-4435 5985);
DISPLAY 0.489362 (-4435 5985);
PAINT MONO (-4435 5985);
FORCEPROP 0 LASTPIN (-4425 5925) $PN CF48
J 2
(-4435 5935);
DISPLAY 0.489362 (-4435 5935);
PAINT MONO (-4435 5935);
FORCEPROP 0 LASTPIN (-4425 5875) $PN CF49
J 2
(-4435 5885);
DISPLAY 0.489362 (-4435 5885);
PAINT MONO (-4435 5885);
FORCEPROP 0 LASTPIN (-4425 5825) $PN CF50
J 2
(-4435 5835);
DISPLAY 0.489362 (-4435 5835);
PAINT MONO (-4435 5835);
FORCEPROP 0 LASTPIN (-4425 5775) $PN CF51
J 2
(-4435 5785);
DISPLAY 0.489362 (-4435 5785);
PAINT MONO (-4435 5785);
FORCEPROP 0 LASTPIN (-4425 5725) $PN CF52
J 2
(-4435 5735);
DISPLAY 0.489362 (-4435 5735);
PAINT MONO (-4435 5735);
FORCEPROP 0 LASTPIN (-4425 5675) $PN CF53
J 2
(-4435 5685);
DISPLAY 0.489362 (-4435 5685);
PAINT MONO (-4435 5685);
FORCEPROP 0 LASTPIN (-4425 5625) $PN CF57
J 2
(-4435 5635);
DISPLAY 0.489362 (-4435 5635);
PAINT MONO (-4435 5635);
FORCEPROP 0 LASTPIN (-4425 5575) $PN CF59
J 2
(-4435 5585);
DISPLAY 0.489362 (-4435 5585);
PAINT MONO (-4435 5585);
FORCEPROP 0 LASTPIN (-4425 5525) $PN CF61
J 2
(-4435 5535);
DISPLAY 0.489362 (-4435 5535);
PAINT MONO (-4435 5535);
FORCEPROP 0 LASTPIN (-4425 5475) $PN CF64
J 2
(-4435 5485);
DISPLAY 0.489362 (-4435 5485);
PAINT MONO (-4435 5485);
FORCEPROP 0 LASTPIN (-4425 5425) $PN CF66
J 2
(-4435 5435);
DISPLAY 0.489362 (-4435 5435);
PAINT MONO (-4435 5435);
FORCEPROP 0 LASTPIN (-4425 5375) $PN CF68
J 2
(-4435 5385);
DISPLAY 0.489362 (-4435 5385);
PAINT MONO (-4435 5385);
FORCEPROP 0 LASTPIN (-4425 5325) $PN CF71
J 2
(-4435 5335);
DISPLAY 0.489362 (-4435 5335);
PAINT MONO (-4435 5335);
FORCEPROP 0 LASTPIN (-4425 5275) $PN CF73
J 2
(-4435 5285);
DISPLAY 0.489362 (-4435 5285);
PAINT MONO (-4435 5285);
FORCEPROP 0 LASTPIN (-4425 5225) $PN CG1
J 2
(-4435 5235);
DISPLAY 0.489362 (-4435 5235);
PAINT MONO (-4435 5235);
FORCEPROP 0 LASTPIN (-4425 5175) $PN CG6
J 2
(-4435 5185);
DISPLAY 0.489362 (-4435 5185);
PAINT MONO (-4435 5185);
FORCEPROP 0 LASTPIN (-4425 5125) $PN CG8
J 2
(-4435 5135);
DISPLAY 0.489362 (-4435 5135);
PAINT MONO (-4435 5135);
FORCEPROP 0 LASTPIN (-4425 5075) $PN CG13
J 2
(-4435 5085);
DISPLAY 0.489362 (-4435 5085);
PAINT MONO (-4435 5085);
FORCEPROP 0 LASTPIN (-4425 5025) $PN CG15
J 2
(-4435 5035);
DISPLAY 0.489362 (-4435 5035);
PAINT MONO (-4435 5035);
FORCEPROP 0 LASTPIN (-4425 4975) $PN CG20
J 2
(-4435 4985);
DISPLAY 0.489362 (-4435 4985);
PAINT MONO (-4435 4985);
FORCEPROP 0 LASTPIN (-4425 4925) $PN CG22
J 2
(-4435 4935);
DISPLAY 0.489362 (-4435 4935);
PAINT MONO (-4435 4935);
FORCEPROP 0 LASTPIN (-4425 4875) $PN CG25
J 2
(-4435 4885);
DISPLAY 0.489362 (-4435 4885);
PAINT MONO (-4435 4885);
FORCEPROP 0 LASTPIN (-4425 4825) $PN CG28
J 2
(-4435 4835);
DISPLAY 0.489362 (-4435 4835);
PAINT MONO (-4435 4835);
FORCEPROP 0 LASTPIN (-4425 4775) $PN CG31
J 2
(-4435 4785);
DISPLAY 0.489362 (-4435 4785);
PAINT MONO (-4435 4785);
FORCEPROP 0 LASTPIN (-4425 4725) $PN CG34
J 2
(-4435 4735);
DISPLAY 0.489362 (-4435 4735);
PAINT MONO (-4435 4735);
FORCEPROP 0 LASTPIN (-4425 4675) $PN CG45
J 2
(-4435 4685);
DISPLAY 0.489362 (-4435 4685);
PAINT MONO (-4435 4685);
FORCEPROP 0 LASTPIN (-4425 4625) $PN CG48
J 2
(-4435 4635);
DISPLAY 0.489362 (-4435 4635);
PAINT MONO (-4435 4635);
FORCEPROP 0 LASTPIN (-4425 4575) $PN CG51
J 2
(-4435 4585);
DISPLAY 0.489362 (-4435 4585);
PAINT MONO (-4435 4585);
FORCEPROP 0 LASTPIN (-4425 4525) $PN CG54
J 2
(-4435 4535);
DISPLAY 0.489362 (-4435 4535);
PAINT MONO (-4435 4535);
FORCEPROP 0 LASTPIN (-4425 4475) $PN CG56
J 2
(-4435 4485);
DISPLAY 0.489362 (-4435 4485);
PAINT MONO (-4435 4485);
FORCEPROP 0 LASTPIN (-4425 4425) $PN CG61
J 2
(-4435 4435);
DISPLAY 0.489362 (-4435 4435);
PAINT MONO (-4435 4435);
FORCEPROP 0 LASTPIN (-4425 4375) $PN CG63
J 2
(-4435 4385);
DISPLAY 0.489362 (-4435 4385);
PAINT MONO (-4435 4385);
FORCEPROP 0 LASTPIN (-4425 4325) $PN CG68
J 2
(-4435 4335);
DISPLAY 0.489362 (-4435 4335);
PAINT MONO (-4435 4335);
FORCEPROP 0 LASTPIN (-4425 4275) $PN CG70
J 2
(-4435 4285);
DISPLAY 0.489362 (-4435 4285);
PAINT MONO (-4435 4285);
FORCEPROP 0 LASTPIN (-4425 4225) $PN CG75
J 2
(-4435 4235);
DISPLAY 0.489362 (-4435 4235);
PAINT MONO (-4435 4235);
FORCEPROP 0 LASTPIN (-4425 4175) $PN CH3
J 2
(-4435 4185);
DISPLAY 0.489362 (-4435 4185);
PAINT MONO (-4435 4185);
FORCEPROP 0 LASTPIN (-4425 4125) $PN CH5
J 2
(-4435 4135);
DISPLAY 0.489362 (-4435 4135);
PAINT MONO (-4435 4135);
FORCEPROP 0 LASTPIN (-4425 4075) $PN CH8
J 2
(-4435 4085);
DISPLAY 0.489362 (-4435 4085);
PAINT MONO (-4435 4085);
FORCEPROP 0 LASTPIN (-4425 4025) $PN CH10
J 2
(-4435 4035);
DISPLAY 0.489362 (-4435 4035);
PAINT MONO (-4435 4035);
FORCEPROP 0 LASTPIN (-4425 3975) $PN CH12
J 2
(-4435 3985);
DISPLAY 0.489362 (-4435 3985);
PAINT MONO (-4435 3985);
FORCEPROP 0 LASTPIN (-4425 3925) $PN CH15
J 2
(-4435 3935);
DISPLAY 0.489362 (-4435 3935);
PAINT MONO (-4435 3935);
FORCEPROP 0 LASTPIN (-4425 3875) $PN CH17
J 2
(-4435 3885);
DISPLAY 0.489362 (-4435 3885);
PAINT MONO (-4435 3885);
FORCEPROP 0 LASTPIN (-4425 3825) $PN CH19
J 2
(-4435 3835);
DISPLAY 0.489362 (-4435 3835);
PAINT MONO (-4435 3835);
FORCEPROP 0 LASTPIN (-4425 3775) $PN CH22
J 2
(-4435 3785);
DISPLAY 0.489362 (-4435 3785);
PAINT MONO (-4435 3785);
FORCEPROP 0 LASTPIN (-4425 3725) $PN CH25
J 2
(-4435 3735);
DISPLAY 0.489362 (-4435 3735);
PAINT MONO (-4435 3735);
FORCEPROP 0 LASTPIN (-4425 3675) $PN CH28
J 2
(-4435 3685);
DISPLAY 0.489362 (-4435 3685);
PAINT MONO (-4435 3685);
FORCEPROP 0 LASTPIN (-4425 3625) $PN CH31
J 2
(-4435 3635);
DISPLAY 0.489362 (-4435 3635);
PAINT MONO (-4435 3635);
FORCEPROP 0 LASTPIN (-4425 3575) $PN CH34
J 2
(-4435 3585);
DISPLAY 0.489362 (-4435 3585);
PAINT MONO (-4435 3585);
FORCEPROP 0 LASTPIN (-4425 3525) $PN CH37
J 2
(-4435 3535);
DISPLAY 0.489362 (-4435 3535);
PAINT MONO (-4435 3535);
FORCEPROP 0 LASTPIN (-4425 3475) $PN CH39
J 2
(-4435 3485);
DISPLAY 0.489362 (-4435 3485);
PAINT MONO (-4435 3485);
FORCEPROP 0 LASTPIN (-4425 3425) $PN CH42
J 2
(-4435 3435);
DISPLAY 0.489362 (-4435 3435);
PAINT MONO (-4435 3435);
FORCEPROP 0 LASTPIN (-4425 3375) $PN CH45
J 2
(-4435 3385);
DISPLAY 0.489362 (-4435 3385);
PAINT MONO (-4435 3385);
FORCEPROP 0 LASTPIN (-4425 3325) $PN CH48
J 2
(-4435 3335);
DISPLAY 0.489362 (-4435 3335);
PAINT MONO (-4435 3335);
FORCEPROP 0 LASTPIN (-4425 3275) $PN CH51
J 2
(-4435 3285);
DISPLAY 0.489362 (-4435 3285);
PAINT MONO (-4435 3285);
FORCEPROP 0 LASTPIN (-4425 3225) $PN CH54
J 2
(-4435 3235);
DISPLAY 0.489362 (-4435 3235);
PAINT MONO (-4435 3235);
FORCEPROP 0 LASTPIN (-4425 3175) $PN CH57
J 2
(-4435 3185);
DISPLAY 0.489362 (-4435 3185);
PAINT MONO (-4435 3185);
FORCEPROP 0 LASTPIN (-4425 3125) $PN CH59
J 2
(-4435 3135);
DISPLAY 0.489362 (-4435 3135);
PAINT MONO (-4435 3135);
FORCEPROP 0 LASTPIN (-4425 3075) $PN CH61
J 2
(-4435 3085);
DISPLAY 0.489362 (-4435 3085);
PAINT MONO (-4435 3085);
FORCEPROP 0 LASTPIN (-4425 3025) $PN CH64
J 2
(-4435 3035);
DISPLAY 0.489362 (-4435 3035);
PAINT MONO (-4435 3035);
FORCEPROP 0 LASTPIN (-4425 2975) $PN CH66
J 2
(-4435 2985);
DISPLAY 0.489362 (-4435 2985);
PAINT MONO (-4435 2985);
FORCEPROP 0 LASTPIN (-4425 2925) $PN CH68
J 2
(-4435 2935);
DISPLAY 0.489362 (-4435 2935);
PAINT MONO (-4435 2935);
FORCEPROP 0 LASTPIN (-4425 2875) $PN CH71
J 2
(-4435 2885);
DISPLAY 0.489362 (-4435 2885);
PAINT MONO (-4435 2885);
FORCEPROP 0 LASTPIN (-4425 2825) $PN CH73
J 2
(-4435 2835);
DISPLAY 0.489362 (-4435 2835);
PAINT MONO (-4435 2835);
FORCEPROP 0 LASTPIN (-4425 2775) $PN CJ1
J 2
(-4435 2785);
DISPLAY 0.489362 (-4435 2785);
PAINT MONO (-4435 2785);
FORCEPROP 0 LASTPIN (-4425 2725) $PN CJ4
J 2
(-4435 2735);
DISPLAY 0.489362 (-4435 2735);
PAINT MONO (-4435 2735);
FORCEPROP 0 LASTPIN (-4425 2675) $PN CJ6
J 2
(-4435 2685);
DISPLAY 0.489362 (-4435 2685);
PAINT MONO (-4435 2685);
FORCEPROP 0 LASTPIN (-4425 2625) $PN CJ8
J 2
(-4435 2635);
DISPLAY 0.489362 (-4435 2635);
PAINT MONO (-4435 2635);
FORCEPROP 0 LASTPIN (-4425 2575) $PN CJ11
J 2
(-4435 2585);
DISPLAY 0.489362 (-4435 2585);
PAINT MONO (-4435 2585);
FORCEPROP 0 LASTPIN (-4425 2525) $PN CJ13
J 2
(-4435 2535);
DISPLAY 0.489362 (-4435 2535);
PAINT MONO (-4435 2535);
FORCEPROP 0 LASTPIN (-4425 2475) $PN CJ15
J 2
(-4435 2485);
DISPLAY 0.489362 (-4435 2485);
PAINT MONO (-4435 2485);
FORCEPROP 0 LASTPIN (-4425 2425) $PN CJ18
J 2
(-4435 2435);
DISPLAY 0.489362 (-4435 2435);
PAINT MONO (-4435 2435);
FORCEPROP 0 LASTPIN (-4425 2375) $PN CJ20
J 2
(-4435 2385);
DISPLAY 0.489362 (-4435 2385);
PAINT MONO (-4435 2385);
FORCEPROP 0 LASTPIN (-4425 2325) $PN CJ23
J 2
(-4435 2335);
DISPLAY 0.489362 (-4435 2335);
PAINT MONO (-4435 2335);
FORCEPROP 0 LASTPIN (-4425 2275) $PN CJ31
J 2
(-4435 2285);
DISPLAY 0.489362 (-4435 2285);
PAINT MONO (-4435 2285);
FORCEPROP 0 LASTPIN (-4425 2225) $PN CJ34
J 2
(-4435 2235);
DISPLAY 0.489362 (-4435 2235);
PAINT MONO (-4435 2235);
FORCEPROP 0 LASTPIN (-4425 2175) $PN CJ35
J 2
(-4435 2185);
DISPLAY 0.489362 (-4435 2185);
PAINT MONO (-4435 2185);
FORCEPROP 0 LASTPIN (-4425 2125) $PN CJ36
J 2
(-4435 2135);
DISPLAY 0.489362 (-4435 2135);
PAINT MONO (-4435 2135);
FORCEPROP 0 LASTPIN (-4425 2075) $PN CJ40
J 2
(-4435 2085);
DISPLAY 0.489362 (-4435 2085);
PAINT MONO (-4435 2085);
FORCEPROP 0 LASTPIN (-4425 2025) $PN CJ41
J 2
(-4435 2035);
DISPLAY 0.489362 (-4435 2035);
PAINT MONO (-4435 2035);
FORCEPROP 0 LASTPIN (-4425 1975) $PN CJ42
J 2
(-4435 1985);
DISPLAY 0.489362 (-4435 1985);
PAINT MONO (-4435 1985);
FORCEPROP 0 LASTPIN (-4425 1925) $PN CJ45
J 2
(-4435 1935);
DISPLAY 0.489362 (-4435 1935);
PAINT MONO (-4435 1935);
FORCEPROP 0 LASTPIN (-4425 1875) $PN CJ56
J 2
(-4435 1885);
DISPLAY 0.489362 (-4435 1885);
PAINT MONO (-4435 1885);
FORCEPROP 0 LASTPIN (-4425 1825) $PN CJ58
J 2
(-4435 1835);
DISPLAY 0.489362 (-4435 1835);
PAINT MONO (-4435 1835);
FORCEPROP 0 LASTPIN (-4425 1775) $PN CJ61
J 2
(-4435 1785);
DISPLAY 0.489362 (-4435 1785);
PAINT MONO (-4435 1785);
FORCEPROP 0 LASTPIN (-4425 1725) $PN CJ63
J 2
(-4435 1735);
DISPLAY 0.489362 (-4435 1735);
PAINT MONO (-4435 1735);
FORCEPROP 0 LASTPIN (-4425 1675) $PN CJ65
J 2
(-4435 1685);
DISPLAY 0.489362 (-4435 1685);
PAINT MONO (-4435 1685);
FORCEPROP 0 LASTPIN (-4425 1625) $PN CJ68
J 2
(-4435 1635);
DISPLAY 0.489362 (-4435 1635);
PAINT MONO (-4435 1635);
FORCEPROP 0 LASTPIN (-4425 1575) $PN CJ70
J 2
(-4435 1585);
DISPLAY 0.489362 (-4435 1585);
PAINT MONO (-4435 1585);
FORCEPROP 0 LASTPIN (-4425 1525) $PN CJ72
J 2
(-4435 1535);
DISPLAY 0.489362 (-4435 1535);
PAINT MONO (-4435 1535);
FORCEPROP 0 LASTPIN (-4425 1475) $PN CJ75
J 2
(-4435 1485);
DISPLAY 0.489362 (-4435 1485);
PAINT MONO (-4435 1485);
FORCEPROP 0 LASTPIN (-4425 1425) $PN CK3
J 2
(-4435 1435);
DISPLAY 0.489362 (-4435 1435);
PAINT MONO (-4435 1435);
FORCEPROP 0 LASTPIN (-4425 1375) $PN CK8
J 2
(-4435 1385);
DISPLAY 0.489362 (-4435 1385);
PAINT MONO (-4435 1385);
FORCEPROP 0 LASTPIN (-4425 1325) $PN CK15
J 2
(-4435 1335);
DISPLAY 0.489362 (-4435 1335);
PAINT MONO (-4435 1335);
FORCEPROP 0 LASTPIN (-4425 1275) $PN CK17
J 2
(-4435 1285);
DISPLAY 0.489362 (-4435 1285);
PAINT MONO (-4435 1285);
FORCEPROP 0 LASTPIN (-4425 1225) $PN CK22
J 2
(-4435 1235);
DISPLAY 0.489362 (-4435 1235);
PAINT MONO (-4435 1235);
FORCEPROP 0 LASTPIN (-4425 1175) $PN CK23
J 2
(-4435 1185);
DISPLAY 0.489362 (-4435 1185);
PAINT MONO (-4435 1185);
FORCEPROP 0 LASTPIN (-4425 1125) $PN CK24
J 2
(-4435 1135);
DISPLAY 0.489362 (-4435 1135);
PAINT MONO (-4435 1135);
FORCEPROP 0 LASTPIN (-4425 1075) $PN CK25
J 2
(-4435 1085);
DISPLAY 0.489362 (-4435 1085);
PAINT MONO (-4435 1085);
FORCEPROP 0 LASTPIN (-4425 1025) $PN CK26
J 2
(-4435 1035);
DISPLAY 0.489362 (-4435 1035);
PAINT MONO (-4435 1035);
FORCEPROP 0 LASTPIN (-4425 975) $PN CK27
J 2
(-4435 985);
DISPLAY 0.489362 (-4435 985);
PAINT MONO (-4435 985);
FORCEPROP 0 LASTPIN (-4425 925) $PN CK28
J 2
(-4435 935);
DISPLAY 0.489362 (-4435 935);
PAINT MONO (-4435 935);
FORCEPROP 0 LASTPIN (-4425 875) $PN CK32
J 2
(-4435 885);
DISPLAY 0.489362 (-4435 885);
PAINT MONO (-4435 885);
FORCEPROP 0 LASTPIN (-4425 825) $PN CK33
J 2
(-4435 835);
DISPLAY 0.489362 (-4435 835);
PAINT MONO (-4435 835);
FORCEPROP 0 LASTPIN (-4425 775) $PN CK34
J 2
(-4435 785);
DISPLAY 0.489362 (-4435 785);
PAINT MONO (-4435 785);
FORCEPROP 0 LASTPIN (-4425 725) $PN CK37
J 2
(-4435 735);
DISPLAY 0.489362 (-4435 735);
PAINT MONO (-4435 735);
FORCEPROP 0 LASTPIN (-4425 675) $PN CK39
J 2
(-4435 685);
DISPLAY 0.489362 (-4435 685);
PAINT MONO (-4435 685);
FORCEPROP 0 LASTPIN (-4425 625) $PN CK42
J 2
(-4435 635);
DISPLAY 0.489362 (-4435 635);
PAINT MONO (-4435 635);
FORCEPROP 0 LASTPIN (-3325 6425) $PN CK43
J 0
(-3315 6435);
DISPLAY 0.489362 (-3315 6435);
PAINT MONO (-3315 6435);
FORCEPROP 0 LASTPIN (-3325 6375) $PN CK44
J 0
(-3315 6385);
DISPLAY 0.489362 (-3315 6385);
PAINT MONO (-3315 6385);
FORCEPROP 0 LASTPIN (-3325 6325) $PN CK45
J 0
(-3315 6335);
DISPLAY 0.489362 (-3315 6335);
PAINT MONO (-3315 6335);
FORCEPROP 0 LASTPIN (-3325 6275) $PN CK48
J 0
(-3315 6285);
DISPLAY 0.489362 (-3315 6285);
PAINT MONO (-3315 6285);
FORCEPROP 0 LASTPIN (-3325 6225) $PN CK49
J 0
(-3315 6235);
DISPLAY 0.489362 (-3315 6235);
PAINT MONO (-3315 6235);
FORCEPROP 0 LASTPIN (-3325 6175) $PN CK50
J 0
(-3315 6185);
DISPLAY 0.489362 (-3315 6185);
PAINT MONO (-3315 6185);
FORCEPROP 0 LASTPIN (-3325 6125) $PN CK51
J 0
(-3315 6135);
DISPLAY 0.489362 (-3315 6135);
PAINT MONO (-3315 6135);
FORCEPROP 0 LASTPIN (-3325 6075) $PN CK52
J 0
(-3315 6085);
DISPLAY 0.489362 (-3315 6085);
PAINT MONO (-3315 6085);
FORCEPROP 0 LASTPIN (-3325 6025) $PN CK53
J 0
(-3315 6035);
DISPLAY 0.489362 (-3315 6035);
PAINT MONO (-3315 6035);
FORCEPROP 0 LASTPIN (-3325 5975) $PN CK54
J 0
(-3315 5985);
DISPLAY 0.489362 (-3315 5985);
PAINT MONO (-3315 5985);
FORCEPROP 0 LASTPIN (-3325 5925) $PN CK59
J 0
(-3315 5935);
DISPLAY 0.489362 (-3315 5935);
PAINT MONO (-3315 5935);
FORCEPROP 0 LASTPIN (-3325 5875) $PN CK61
J 0
(-3315 5885);
DISPLAY 0.489362 (-3315 5885);
PAINT MONO (-3315 5885);
FORCEPROP 0 LASTPIN (-3325 5825) $PN CK66
J 0
(-3315 5835);
DISPLAY 0.489362 (-3315 5835);
PAINT MONO (-3315 5835);
FORCEPROP 0 LASTPIN (-3325 5775) $PN CK68
J 0
(-3315 5785);
DISPLAY 0.489362 (-3315 5785);
PAINT MONO (-3315 5785);
FORCEPROP 0 LASTPIN (-3325 5725) $PN CK73
J 0
(-3315 5735);
DISPLAY 0.489362 (-3315 5735);
PAINT MONO (-3315 5735);
FORCEPROP 0 LASTPIN (-3325 5675) $PN CL1
J 0
(-3315 5685);
DISPLAY 0.489362 (-3315 5685);
PAINT MONO (-3315 5685);
FORCEPROP 0 LASTPIN (-3325 5625) $PN CL4
J 0
(-3315 5635);
DISPLAY 0.489362 (-3315 5635);
PAINT MONO (-3315 5635);
FORCEPROP 0 LASTPIN (-3325 5575) $PN CL6
J 0
(-3315 5585);
DISPLAY 0.489362 (-3315 5585);
PAINT MONO (-3315 5585);
FORCEPROP 0 LASTPIN (-3325 5525) $PN CL8
J 0
(-3315 5535);
DISPLAY 0.489362 (-3315 5535);
PAINT MONO (-3315 5535);
FORCEPROP 0 LASTPIN (-3325 5475) $PN CL11
J 0
(-3315 5485);
DISPLAY 0.489362 (-3315 5485);
PAINT MONO (-3315 5485);
FORCEPROP 0 LASTPIN (-3325 5425) $PN CL13
J 0
(-3315 5435);
DISPLAY 0.489362 (-3315 5435);
PAINT MONO (-3315 5435);
FORCEPROP 0 LASTPIN (-3325 5375) $PN CL15
J 0
(-3315 5385);
DISPLAY 0.489362 (-3315 5385);
PAINT MONO (-3315 5385);
FORCEPROP 0 LASTPIN (-3325 5325) $PN CL18
J 0
(-3315 5335);
DISPLAY 0.489362 (-3315 5335);
PAINT MONO (-3315 5335);
FORCEPROP 0 LASTPIN (-3325 5275) $PN CL20
J 0
(-3315 5285);
DISPLAY 0.489362 (-3315 5285);
PAINT MONO (-3315 5285);
FORCEPROP 0 LASTPIN (-3325 5225) $PN CL22
J 0
(-3315 5235);
DISPLAY 0.489362 (-3315 5235);
PAINT MONO (-3315 5235);
FORCEPROP 0 LASTPIN (-3325 5175) $PN CL25
J 0
(-3315 5185);
DISPLAY 0.489362 (-3315 5185);
PAINT MONO (-3315 5185);
FORCEPROP 0 LASTPIN (-3325 5125) $PN CL28
J 0
(-3315 5135);
DISPLAY 0.489362 (-3315 5135);
PAINT MONO (-3315 5135);
FORCEPROP 0 LASTPIN (-3325 5075) $PN CL31
J 0
(-3315 5085);
DISPLAY 0.489362 (-3315 5085);
PAINT MONO (-3315 5085);
FORCEPROP 0 LASTPIN (-3325 5025) $PN CL34
J 0
(-3315 5035);
DISPLAY 0.489362 (-3315 5035);
PAINT MONO (-3315 5035);
FORCEPROP 0 LASTPIN (-3325 4975) $PN CL35
J 0
(-3315 4985);
DISPLAY 0.489362 (-3315 4985);
PAINT MONO (-3315 4985);
FORCEPROP 0 LASTPIN (-3325 4925) $PN CL36
J 0
(-3315 4935);
DISPLAY 0.489362 (-3315 4935);
PAINT MONO (-3315 4935);
FORCEPROP 0 LASTPIN (-3325 4875) $PN CL40
J 0
(-3315 4885);
DISPLAY 0.489362 (-3315 4885);
PAINT MONO (-3315 4885);
FORCEPROP 0 LASTPIN (-3325 4825) $PN CL41
J 0
(-3315 4835);
DISPLAY 0.489362 (-3315 4835);
PAINT MONO (-3315 4835);
FORCEPROP 0 LASTPIN (-3325 4775) $PN CL42
J 0
(-3315 4785);
DISPLAY 0.489362 (-3315 4785);
PAINT MONO (-3315 4785);
FORCEPROP 0 LASTPIN (-3325 4725) $PN CL45
J 0
(-3315 4735);
DISPLAY 0.489362 (-3315 4735);
PAINT MONO (-3315 4735);
FORCEPROP 0 LASTPIN (-3325 4675) $PN CL48
J 0
(-3315 4685);
DISPLAY 0.489362 (-3315 4685);
PAINT MONO (-3315 4685);
FORCEPROP 0 LASTPIN (-3325 4625) $PN CL51
J 0
(-3315 4635);
DISPLAY 0.489362 (-3315 4635);
PAINT MONO (-3315 4635);
FORCEPROP 0 LASTPIN (-3325 4575) $PN CL54
J 0
(-3315 4585);
DISPLAY 0.489362 (-3315 4585);
PAINT MONO (-3315 4585);
FORCEPROP 0 LASTPIN (-3325 4525) $PN CL56
J 0
(-3315 4535);
DISPLAY 0.489362 (-3315 4535);
PAINT MONO (-3315 4535);
FORCEPROP 0 LASTPIN (-3325 4475) $PN CL58
J 0
(-3315 4485);
DISPLAY 0.489362 (-3315 4485);
PAINT MONO (-3315 4485);
FORCEPROP 0 LASTPIN (-3325 4425) $PN CL61
J 0
(-3315 4435);
DISPLAY 0.489362 (-3315 4435);
PAINT MONO (-3315 4435);
FORCEPROP 0 LASTPIN (-3325 4375) $PN CL63
J 0
(-3315 4385);
DISPLAY 0.489362 (-3315 4385);
PAINT MONO (-3315 4385);
FORCEPROP 0 LASTPIN (-3325 4325) $PN CL65
J 0
(-3315 4335);
DISPLAY 0.489362 (-3315 4335);
PAINT MONO (-3315 4335);
FORCEPROP 0 LASTPIN (-3325 4275) $PN CL68
J 0
(-3315 4285);
DISPLAY 0.489362 (-3315 4285);
PAINT MONO (-3315 4285);
FORCEPROP 0 LASTPIN (-3325 4225) $PN CL70
J 0
(-3315 4235);
DISPLAY 0.489362 (-3315 4235);
PAINT MONO (-3315 4235);
FORCEPROP 0 LASTPIN (-3325 4175) $PN CL72
J 0
(-3315 4185);
DISPLAY 0.489362 (-3315 4185);
PAINT MONO (-3315 4185);
FORCEPROP 0 LASTPIN (-3325 4125) $PN CL75
J 0
(-3315 4135);
DISPLAY 0.489362 (-3315 4135);
PAINT MONO (-3315 4135);
FORCEPROP 0 LASTPIN (-3325 4075) $PN CM3
J 0
(-3315 4085);
DISPLAY 0.489362 (-3315 4085);
PAINT MONO (-3315 4085);
FORCEPROP 0 LASTPIN (-3325 4025) $PN CM5
J 0
(-3315 4035);
DISPLAY 0.489362 (-3315 4035);
PAINT MONO (-3315 4035);
FORCEPROP 0 LASTPIN (-3325 3975) $PN CM8
J 0
(-3315 3985);
DISPLAY 0.489362 (-3315 3985);
PAINT MONO (-3315 3985);
FORCEPROP 0 LASTPIN (-3325 3925) $PN CM10
J 0
(-3315 3935);
DISPLAY 0.489362 (-3315 3935);
PAINT MONO (-3315 3935);
FORCEPROP 0 LASTPIN (-3325 3875) $PN CM12
J 0
(-3315 3885);
DISPLAY 0.489362 (-3315 3885);
PAINT MONO (-3315 3885);
FORCEPROP 0 LASTPIN (-3325 3825) $PN CM15
J 0
(-3315 3835);
DISPLAY 0.489362 (-3315 3835);
PAINT MONO (-3315 3835);
FORCEPROP 0 LASTPIN (-3325 3775) $PN CM17
J 0
(-3315 3785);
DISPLAY 0.489362 (-3315 3785);
PAINT MONO (-3315 3785);
FORCEPROP 0 LASTPIN (-3325 3725) $PN CM19
J 0
(-3315 3735);
DISPLAY 0.489362 (-3315 3735);
PAINT MONO (-3315 3735);
FORCEPROP 0 LASTPIN (-3325 3675) $PN CM23
J 0
(-3315 3685);
DISPLAY 0.489362 (-3315 3685);
PAINT MONO (-3315 3685);
FORCEPROP 0 LASTPIN (-3325 3625) $PN CM24
J 0
(-3315 3635);
DISPLAY 0.489362 (-3315 3635);
PAINT MONO (-3315 3635);
FORCEPROP 0 LASTPIN (-3325 3575) $PN CM25
J 0
(-3315 3585);
DISPLAY 0.489362 (-3315 3585);
PAINT MONO (-3315 3585);
FORCEPROP 0 LASTPIN (-3325 3525) $PN CM26
J 0
(-3315 3535);
DISPLAY 0.489362 (-3315 3535);
PAINT MONO (-3315 3535);
FORCEPROP 0 LASTPIN (-3325 3475) $PN CM27
J 0
(-3315 3485);
DISPLAY 0.489362 (-3315 3485);
PAINT MONO (-3315 3485);
FORCEPROP 0 LASTPIN (-3325 3425) $PN CM28
J 0
(-3315 3435);
DISPLAY 0.489362 (-3315 3435);
PAINT MONO (-3315 3435);
FORCEPROP 0 LASTPIN (-3325 3375) $PN CM29
J 0
(-3315 3385);
DISPLAY 0.489362 (-3315 3385);
PAINT MONO (-3315 3385);
FORCEPROP 0 LASTPIN (-3325 3325) $PN CM30
J 0
(-3315 3335);
DISPLAY 0.489362 (-3315 3335);
PAINT MONO (-3315 3335);
FORCEPROP 0 LASTPIN (-3325 3275) $PN CM31
J 0
(-3315 3285);
DISPLAY 0.489362 (-3315 3285);
PAINT MONO (-3315 3285);
FORCEPROP 0 LASTPIN (-3325 3225) $PN CM32
J 0
(-3315 3235);
DISPLAY 0.489362 (-3315 3235);
PAINT MONO (-3315 3235);
FORCEPROP 0 LASTPIN (-3325 3175) $PN CM33
J 0
(-3315 3185);
DISPLAY 0.489362 (-3315 3185);
PAINT MONO (-3315 3185);
FORCEPROP 0 LASTPIN (-3325 3125) $PN CM34
J 0
(-3315 3135);
DISPLAY 0.489362 (-3315 3135);
PAINT MONO (-3315 3135);
FORCEPROP 0 LASTPIN (-3325 3075) $PN CM37
J 0
(-3315 3085);
DISPLAY 0.489362 (-3315 3085);
PAINT MONO (-3315 3085);
FORCEPROP 0 LASTPIN (-3325 3025) $PN CM39
J 0
(-3315 3035);
DISPLAY 0.489362 (-3315 3035);
PAINT MONO (-3315 3035);
FORCEPROP 0 LASTPIN (-3325 2975) $PN CM42
J 0
(-3315 2985);
DISPLAY 0.489362 (-3315 2985);
PAINT MONO (-3315 2985);
FORCEPROP 0 LASTPIN (-3325 2925) $PN CM43
J 0
(-3315 2935);
DISPLAY 0.489362 (-3315 2935);
PAINT MONO (-3315 2935);
FORCEPROP 0 LASTPIN (-3325 2875) $PN CM44
J 0
(-3315 2885);
DISPLAY 0.489362 (-3315 2885);
PAINT MONO (-3315 2885);
FORCEPROP 0 LASTPIN (-3325 2825) $PN CM45
J 0
(-3315 2835);
DISPLAY 0.489362 (-3315 2835);
PAINT MONO (-3315 2835);
FORCEPROP 0 LASTPIN (-3325 2775) $PN CM46
J 0
(-3315 2785);
DISPLAY 0.489362 (-3315 2785);
PAINT MONO (-3315 2785);
FORCEPROP 0 LASTPIN (-3325 2725) $PN CM47
J 0
(-3315 2735);
DISPLAY 0.489362 (-3315 2735);
PAINT MONO (-3315 2735);
FORCEPROP 0 LASTPIN (-3325 2675) $PN CM48
J 0
(-3315 2685);
DISPLAY 0.489362 (-3315 2685);
PAINT MONO (-3315 2685);
FORCEPROP 0 LASTPIN (-3325 2625) $PN CM49
J 0
(-3315 2635);
DISPLAY 0.489362 (-3315 2635);
PAINT MONO (-3315 2635);
FORCEPROP 0 LASTPIN (-3325 2575) $PN CM51
J 0
(-3315 2585);
DISPLAY 0.489362 (-3315 2585);
PAINT MONO (-3315 2585);
FORCEPROP 0 LASTPIN (-3325 2525) $PN CM52
J 0
(-3315 2535);
DISPLAY 0.489362 (-3315 2535);
PAINT MONO (-3315 2535);
FORCEPROP 0 LASTPIN (-3325 2475) $PN CM53
J 0
(-3315 2485);
DISPLAY 0.489362 (-3315 2485);
PAINT MONO (-3315 2485);
FORCEPROP 0 LASTPIN (-3325 2425) $PN CM57
J 0
(-3315 2435);
DISPLAY 0.489362 (-3315 2435);
PAINT MONO (-3315 2435);
FORCEPROP 0 LASTPIN (-3325 2375) $PN CM59
J 0
(-3315 2385);
DISPLAY 0.489362 (-3315 2385);
PAINT MONO (-3315 2385);
FORCEPROP 0 LASTPIN (-3325 2325) $PN CM61
J 0
(-3315 2335);
DISPLAY 0.489362 (-3315 2335);
PAINT MONO (-3315 2335);
FORCEPROP 0 LASTPIN (-3325 2275) $PN CM64
J 0
(-3315 2285);
DISPLAY 0.489362 (-3315 2285);
PAINT MONO (-3315 2285);
FORCEPROP 0 LASTPIN (-3325 2225) $PN CM66
J 0
(-3315 2235);
DISPLAY 0.489362 (-3315 2235);
PAINT MONO (-3315 2235);
FORCEPROP 0 LASTPIN (-3325 2175) $PN CM68
J 0
(-3315 2185);
DISPLAY 0.489362 (-3315 2185);
PAINT MONO (-3315 2185);
FORCEPROP 0 LASTPIN (-3325 2125) $PN CM71
J 0
(-3315 2135);
DISPLAY 0.489362 (-3315 2135);
PAINT MONO (-3315 2135);
FORCEPROP 0 LASTPIN (-3325 2075) $PN CM73
J 0
(-3315 2085);
DISPLAY 0.489362 (-3315 2085);
PAINT MONO (-3315 2085);
FORCEPROP 0 LASTPIN (-3325 2025) $PN CN1
J 0
(-3315 2035);
DISPLAY 0.489362 (-3315 2035);
PAINT MONO (-3315 2035);
FORCEPROP 0 LASTPIN (-3325 1975) $PN CN6
J 0
(-3315 1985);
DISPLAY 0.489362 (-3315 1985);
PAINT MONO (-3315 1985);
FORCEPROP 0 LASTPIN (-3325 1925) $PN CN8
J 0
(-3315 1935);
DISPLAY 0.489362 (-3315 1935);
PAINT MONO (-3315 1935);
FORCEPROP 0 LASTPIN (-3325 1875) $PN CN13
J 0
(-3315 1885);
DISPLAY 0.489362 (-3315 1885);
PAINT MONO (-3315 1885);
FORCEPROP 0 LASTPIN (-3325 1825) $PN CN15
J 0
(-3315 1835);
DISPLAY 0.489362 (-3315 1835);
PAINT MONO (-3315 1835);
FORCEPROP 0 LASTPIN (-3325 1775) $PN CN20
J 0
(-3315 1785);
DISPLAY 0.489362 (-3315 1785);
PAINT MONO (-3315 1785);
FORCEPROP 0 LASTPIN (-3325 1725) $PN CN22
J 0
(-3315 1735);
DISPLAY 0.489362 (-3315 1735);
PAINT MONO (-3315 1735);
FORCEPROP 0 LASTPIN (-3325 1675) $PN CN25
J 0
(-3315 1685);
DISPLAY 0.489362 (-3315 1685);
PAINT MONO (-3315 1685);
FORCEPROP 0 LASTPIN (-3325 1625) $PN CN28
J 0
(-3315 1635);
DISPLAY 0.489362 (-3315 1635);
PAINT MONO (-3315 1635);
FORCEPROP 0 LASTPIN (-3325 1575) $PN CN31
J 0
(-3315 1585);
DISPLAY 0.489362 (-3315 1585);
PAINT MONO (-3315 1585);
FORCEPROP 0 LASTPIN (-3325 1525) $PN CN34
J 0
(-3315 1535);
DISPLAY 0.489362 (-3315 1535);
PAINT MONO (-3315 1535);
FORCEPROP 0 LASTPIN (-3325 1475) $PN CN42
J 0
(-3315 1485);
DISPLAY 0.489362 (-3315 1485);
PAINT MONO (-3315 1485);
FORCEPROP 0 LASTPIN (-3325 1425) $PN CN45
J 0
(-3315 1435);
DISPLAY 0.489362 (-3315 1435);
PAINT MONO (-3315 1435);
FORCEPROP 0 LASTPIN (-3325 1375) $PN CN48
J 0
(-3315 1385);
DISPLAY 0.489362 (-3315 1385);
PAINT MONO (-3315 1385);
FORCEPROP 0 LASTPIN (-3325 1325) $PN CN51
J 0
(-3315 1335);
DISPLAY 0.489362 (-3315 1335);
PAINT MONO (-3315 1335);
FORCEPROP 0 LASTPIN (-3325 1275) $PN CN56
J 0
(-3315 1285);
DISPLAY 0.489362 (-3315 1285);
PAINT MONO (-3315 1285);
FORCEPROP 0 LASTPIN (-3325 1225) $PN CN61
J 0
(-3315 1235);
DISPLAY 0.489362 (-3315 1235);
PAINT MONO (-3315 1235);
FORCEPROP 0 LASTPIN (-3325 1175) $PN CN63
J 0
(-3315 1185);
DISPLAY 0.489362 (-3315 1185);
PAINT MONO (-3315 1185);
FORCEPROP 0 LASTPIN (-3325 1125) $PN CN68
J 0
(-3315 1135);
DISPLAY 0.489362 (-3315 1135);
PAINT MONO (-3315 1135);
FORCEPROP 0 LASTPIN (-3325 1075) $PN CN70
J 0
(-3315 1085);
DISPLAY 0.489362 (-3315 1085);
PAINT MONO (-3315 1085);
FORCEPROP 0 LASTPIN (-3325 1025) $PN CN75
J 0
(-3315 1035);
DISPLAY 0.489362 (-3315 1035);
PAINT MONO (-3315 1035);
FORCEPROP 0 LASTPIN (-3325 975) $PN CP3
J 0
(-3315 985);
DISPLAY 0.489362 (-3315 985);
PAINT MONO (-3315 985);
FORCEPROP 0 LASTPIN (-3325 925) $PN CP5
J 0
(-3315 935);
DISPLAY 0.489362 (-3315 935);
PAINT MONO (-3315 935);
FORCEPROP 0 LASTPIN (-3325 875) $PN CP8
J 0
(-3315 885);
DISPLAY 0.489362 (-3315 885);
PAINT MONO (-3315 885);
FORCEPROP 0 LASTPIN (-3325 825) $PN CP10
J 0
(-3315 835);
DISPLAY 0.489362 (-3315 835);
PAINT MONO (-3315 835);
FORCEPROP 0 LASTPIN (-3325 775) $PN CP12
J 0
(-3315 785);
DISPLAY 0.489362 (-3315 785);
PAINT MONO (-3315 785);
FORCEPROP 0 LASTPIN (-3325 725) $PN CP15
J 0
(-3315 735);
DISPLAY 0.489362 (-3315 735);
PAINT MONO (-3315 735);
FORCEPROP 0 LASTPIN (-3325 675) $PN CP17
J 0
(-3315 685);
DISPLAY 0.489362 (-3315 685);
PAINT MONO (-3315 685);
FORCEPROP 0 LASTPIN (-3325 625) $PN CP19
J 0
(-3315 635);
DISPLAY 0.489362 (-3315 635);
PAINT MONO (-3315 635);
FORCEPROP 2 LAST PART_TYPE SMLF
J 0
(-4500 6675);
DISPLAY 1.021277 (-4500 6675);
FORCEPROP 1 LAST MATERIAL IO
J 0
(-4270 6557);
DISPLAY 0.489362 (-4270 6557);
PAINT SKYBLUE (-4270 6557);
FORCEPROP 2 LAST VALUE SOCKET6096_13568-001
J 0
(-4275 6600);
DISPLAY 0.489362 (-4275 6600);
PAINT SKYBLUE (-4275 6600);
FORCEPROP 2 LAST CDS_LIB pure_quanta
J 0
(-3875 3475);
DISPLAY INVISIBLE (-3875 3475);
FORCEPROP 1 LAST CDS_LMAN_SYM_OUTLINE -400,3050,400,-3050
J 0
(-3875 3475);
DISPLAY 0.468085 (-3875 3475);
PAINT GREEN (-3875 3475);
DISPLAY INVISIBLE (-3875 3475);
FORCEPROP 1 LAST NEEDS_NO_SIZE TRUE
J 0
(-3875 3475);
DISPLAY 0.723404 (-3875 3475);
PAINT GREEN (-3875 3475);
DISPLAY INVISIBLE (-3875 3475);
FORCEPROP 1 LAST PATH I3
J 0
(-3875 3475);
DISPLAY 0.723404 (-3875 3475);
PAINT GREEN (-3875 3475);
DISPLAY INVISIBLE (-3875 3475);
FORCEPROP 1 LAST PART_NUMBER DGA^6000030
J 0
(-4275 6700);
DISPLAY 0.489362 (-4275 6700);
PAINT SKYBLUE (-4275 6700);
DISPLAY INVISIBLE (-4275 6700);
FORCEADD GENOA_SP5..39
(-1800 3500);
FORCEPROP 1 LAST LOCATION U26
J 0
(-2200 6650);
DISPLAY 0.489362 (-2200 6650);
PAINT SKYBLUE (-2200 6650);
FORCEPROP 0 LAST $SEC 39
J 0
(-2175 6900);
DISPLAY 0.680851 (-2175 6900);
PAINT MONO (-2175 6900);
DISPLAY INVISIBLE (-2175 6900);
FORCEPROP 0 LAST CDS_SEC 39
J 0
(-2175 6900);
DISPLAY 1.021277 (-2175 6900);
DISPLAY INVISIBLE (-2175 6900);
FORCEPROP 0 LASTPIN (-1250 550) $PN CP22
J 0
(-1240 560);
DISPLAY 0.489362 (-1240 560);
PAINT MONO (-1240 560);
FORCEPROP 0 LASTPIN (-1250 600) $PN CP25
J 0
(-1240 610);
DISPLAY 0.489362 (-1240 610);
PAINT MONO (-1240 610);
FORCEPROP 0 LASTPIN (-1250 650) $PN CP28
J 0
(-1240 660);
DISPLAY 0.489362 (-1240 660);
PAINT MONO (-1240 660);
FORCEPROP 0 LASTPIN (-1250 700) $PN CP31
J 0
(-1240 710);
DISPLAY 0.489362 (-1240 710);
PAINT MONO (-1240 710);
FORCEPROP 0 LASTPIN (-1250 750) $PN CP34
J 0
(-1240 760);
DISPLAY 0.489362 (-1240 760);
PAINT MONO (-1240 760);
FORCEPROP 0 LASTPIN (-1250 800) $PN CP37
J 0
(-1240 810);
DISPLAY 0.489362 (-1240 810);
PAINT MONO (-1240 810);
FORCEPROP 0 LASTPIN (-1250 850) $PN CP39
J 0
(-1240 860);
DISPLAY 0.489362 (-1240 860);
PAINT MONO (-1240 860);
FORCEPROP 0 LASTPIN (-1250 900) $PN CP42
J 0
(-1240 910);
DISPLAY 0.489362 (-1240 910);
PAINT MONO (-1240 910);
FORCEPROP 0 LASTPIN (-1250 950) $PN CP45
J 0
(-1240 960);
DISPLAY 0.489362 (-1240 960);
PAINT MONO (-1240 960);
FORCEPROP 0 LASTPIN (-1250 1000) $PN CP48
J 0
(-1240 1010);
DISPLAY 0.489362 (-1240 1010);
PAINT MONO (-1240 1010);
FORCEPROP 0 LASTPIN (-1250 1050) $PN CP51
J 0
(-1240 1060);
DISPLAY 0.489362 (-1240 1060);
PAINT MONO (-1240 1060);
FORCEPROP 0 LASTPIN (-1250 1100) $PN CP54
J 0
(-1240 1110);
DISPLAY 0.489362 (-1240 1110);
PAINT MONO (-1240 1110);
FORCEPROP 0 LASTPIN (-1250 1150) $PN CP57
J 0
(-1240 1160);
DISPLAY 0.489362 (-1240 1160);
PAINT MONO (-1240 1160);
FORCEPROP 0 LASTPIN (-1250 1200) $PN CP59
J 0
(-1240 1210);
DISPLAY 0.489362 (-1240 1210);
PAINT MONO (-1240 1210);
FORCEPROP 0 LASTPIN (-1250 1250) $PN CP61
J 0
(-1240 1260);
DISPLAY 0.489362 (-1240 1260);
PAINT MONO (-1240 1260);
FORCEPROP 0 LASTPIN (-1250 1300) $PN CP64
J 0
(-1240 1310);
DISPLAY 0.489362 (-1240 1310);
PAINT MONO (-1240 1310);
FORCEPROP 0 LASTPIN (-1250 1350) $PN CP66
J 0
(-1240 1360);
DISPLAY 0.489362 (-1240 1360);
PAINT MONO (-1240 1360);
FORCEPROP 0 LASTPIN (-1250 1400) $PN CP68
J 0
(-1240 1410);
DISPLAY 0.489362 (-1240 1410);
PAINT MONO (-1240 1410);
FORCEPROP 0 LASTPIN (-1250 1450) $PN CP71
J 0
(-1240 1460);
DISPLAY 0.489362 (-1240 1460);
PAINT MONO (-1240 1460);
FORCEPROP 0 LASTPIN (-1250 1500) $PN CP73
J 0
(-1240 1510);
DISPLAY 0.489362 (-1240 1510);
PAINT MONO (-1240 1510);
FORCEPROP 0 LASTPIN (-1250 1550) $PN CR1
J 0
(-1240 1560);
DISPLAY 0.489362 (-1240 1560);
PAINT MONO (-1240 1560);
FORCEPROP 0 LASTPIN (-1250 1600) $PN CR4
J 0
(-1240 1610);
DISPLAY 0.489362 (-1240 1610);
PAINT MONO (-1240 1610);
FORCEPROP 0 LASTPIN (-1250 1650) $PN CR6
J 0
(-1240 1660);
DISPLAY 0.489362 (-1240 1660);
PAINT MONO (-1240 1660);
FORCEPROP 0 LASTPIN (-1250 1700) $PN CR8
J 0
(-1240 1710);
DISPLAY 0.489362 (-1240 1710);
PAINT MONO (-1240 1710);
FORCEPROP 0 LASTPIN (-1250 1750) $PN CR11
J 0
(-1240 1760);
DISPLAY 0.489362 (-1240 1760);
PAINT MONO (-1240 1760);
FORCEPROP 0 LASTPIN (-1250 1800) $PN CR13
J 0
(-1240 1810);
DISPLAY 0.489362 (-1240 1810);
PAINT MONO (-1240 1810);
FORCEPROP 0 LASTPIN (-1250 1850) $PN CR15
J 0
(-1240 1860);
DISPLAY 0.489362 (-1240 1860);
PAINT MONO (-1240 1860);
FORCEPROP 0 LASTPIN (-1250 1900) $PN CR18
J 0
(-1240 1910);
DISPLAY 0.489362 (-1240 1910);
PAINT MONO (-1240 1910);
FORCEPROP 0 LASTPIN (-1250 1950) $PN CR20
J 0
(-1240 1960);
DISPLAY 0.489362 (-1240 1960);
PAINT MONO (-1240 1960);
FORCEPROP 0 LASTPIN (-1250 2000) $PN CR22
J 0
(-1240 2010);
DISPLAY 0.489362 (-1240 2010);
PAINT MONO (-1240 2010);
FORCEPROP 0 LASTPIN (-1250 2050) $PN CR25
J 0
(-1240 2060);
DISPLAY 0.489362 (-1240 2060);
PAINT MONO (-1240 2060);
FORCEPROP 0 LASTPIN (-1250 2100) $PN CR28
J 0
(-1240 2110);
DISPLAY 0.489362 (-1240 2110);
PAINT MONO (-1240 2110);
FORCEPROP 0 LASTPIN (-1250 2150) $PN CR31
J 0
(-1240 2160);
DISPLAY 0.489362 (-1240 2160);
PAINT MONO (-1240 2160);
FORCEPROP 0 LASTPIN (-1250 2200) $PN CR34
J 0
(-1240 2210);
DISPLAY 0.489362 (-1240 2210);
PAINT MONO (-1240 2210);
FORCEPROP 0 LASTPIN (-1250 2250) $PN CR35
J 0
(-1240 2260);
DISPLAY 0.489362 (-1240 2260);
PAINT MONO (-1240 2260);
FORCEPROP 0 LASTPIN (-1250 2300) $PN CR36
J 0
(-1240 2310);
DISPLAY 0.489362 (-1240 2310);
PAINT MONO (-1240 2310);
FORCEPROP 0 LASTPIN (-1250 2350) $PN CR40
J 0
(-1240 2360);
DISPLAY 0.489362 (-1240 2360);
PAINT MONO (-1240 2360);
FORCEPROP 0 LASTPIN (-1250 2400) $PN CR41
J 0
(-1240 2410);
DISPLAY 0.489362 (-1240 2410);
PAINT MONO (-1240 2410);
FORCEPROP 0 LASTPIN (-1250 2450) $PN CR42
J 0
(-1240 2460);
DISPLAY 0.489362 (-1240 2460);
PAINT MONO (-1240 2460);
FORCEPROP 0 LASTPIN (-1250 2500) $PN CR45
J 0
(-1240 2510);
DISPLAY 0.489362 (-1240 2510);
PAINT MONO (-1240 2510);
FORCEPROP 0 LASTPIN (-1250 2550) $PN CR48
J 0
(-1240 2560);
DISPLAY 0.489362 (-1240 2560);
PAINT MONO (-1240 2560);
FORCEPROP 0 LASTPIN (-1250 2600) $PN CR51
J 0
(-1240 2610);
DISPLAY 0.489362 (-1240 2610);
PAINT MONO (-1240 2610);
FORCEPROP 0 LASTPIN (-1250 2650) $PN CR54
J 0
(-1240 2660);
DISPLAY 0.489362 (-1240 2660);
PAINT MONO (-1240 2660);
FORCEPROP 0 LASTPIN (-1250 2700) $PN CR56
J 0
(-1240 2710);
DISPLAY 0.489362 (-1240 2710);
PAINT MONO (-1240 2710);
FORCEPROP 0 LASTPIN (-1250 2750) $PN CR58
J 0
(-1240 2760);
DISPLAY 0.489362 (-1240 2760);
PAINT MONO (-1240 2760);
FORCEPROP 0 LASTPIN (-1250 2800) $PN CR61
J 0
(-1240 2810);
DISPLAY 0.489362 (-1240 2810);
PAINT MONO (-1240 2810);
FORCEPROP 0 LASTPIN (-1250 2850) $PN CR63
J 0
(-1240 2860);
DISPLAY 0.489362 (-1240 2860);
PAINT MONO (-1240 2860);
FORCEPROP 0 LASTPIN (-1250 2900) $PN CR65
J 0
(-1240 2910);
DISPLAY 0.489362 (-1240 2910);
PAINT MONO (-1240 2910);
FORCEPROP 0 LASTPIN (-1250 2950) $PN CR68
J 0
(-1240 2960);
DISPLAY 0.489362 (-1240 2960);
PAINT MONO (-1240 2960);
FORCEPROP 0 LASTPIN (-1250 3000) $PN CR70
J 0
(-1240 3010);
DISPLAY 0.489362 (-1240 3010);
PAINT MONO (-1240 3010);
FORCEPROP 0 LASTPIN (-1250 3050) $PN CR72
J 0
(-1240 3060);
DISPLAY 0.489362 (-1240 3060);
PAINT MONO (-1240 3060);
FORCEPROP 0 LASTPIN (-1250 3100) $PN CR75
J 0
(-1240 3110);
DISPLAY 0.489362 (-1240 3110);
PAINT MONO (-1240 3110);
FORCEPROP 0 LASTPIN (-1250 3150) $PN CT3
J 0
(-1240 3160);
DISPLAY 0.489362 (-1240 3160);
PAINT MONO (-1240 3160);
FORCEPROP 0 LASTPIN (-1250 3200) $PN CT8
J 0
(-1240 3210);
DISPLAY 0.489362 (-1240 3210);
PAINT MONO (-1240 3210);
FORCEPROP 0 LASTPIN (-1250 3250) $PN CT10
J 0
(-1240 3260);
DISPLAY 0.489362 (-1240 3260);
PAINT MONO (-1240 3260);
FORCEPROP 0 LASTPIN (-1250 3300) $PN CT15
J 0
(-1240 3310);
DISPLAY 0.489362 (-1240 3310);
PAINT MONO (-1240 3310);
FORCEPROP 0 LASTPIN (-1250 3350) $PN CT17
J 0
(-1240 3360);
DISPLAY 0.489362 (-1240 3360);
PAINT MONO (-1240 3360);
FORCEPROP 0 LASTPIN (-1250 3400) $PN CT23
J 0
(-1240 3410);
DISPLAY 0.489362 (-1240 3410);
PAINT MONO (-1240 3410);
FORCEPROP 0 LASTPIN (-1250 3450) $PN CT24
J 0
(-1240 3460);
DISPLAY 0.489362 (-1240 3460);
PAINT MONO (-1240 3460);
FORCEPROP 0 LASTPIN (-1250 3500) $PN CT25
J 0
(-1240 3510);
DISPLAY 0.489362 (-1240 3510);
PAINT MONO (-1240 3510);
FORCEPROP 0 LASTPIN (-1250 3550) $PN CT26
J 0
(-1240 3560);
DISPLAY 0.489362 (-1240 3560);
PAINT MONO (-1240 3560);
FORCEPROP 0 LASTPIN (-1250 3600) $PN CT27
J 0
(-1240 3610);
DISPLAY 0.489362 (-1240 3610);
PAINT MONO (-1240 3610);
FORCEPROP 0 LASTPIN (-1250 3650) $PN CT28
J 0
(-1240 3660);
DISPLAY 0.489362 (-1240 3660);
PAINT MONO (-1240 3660);
FORCEPROP 0 LASTPIN (-1250 3700) $PN CT29
J 0
(-1240 3710);
DISPLAY 0.489362 (-1240 3710);
PAINT MONO (-1240 3710);
FORCEPROP 0 LASTPIN (-1250 3750) $PN CT30
J 0
(-1240 3760);
DISPLAY 0.489362 (-1240 3760);
PAINT MONO (-1240 3760);
FORCEPROP 0 LASTPIN (-1250 3800) $PN CT31
J 0
(-1240 3810);
DISPLAY 0.489362 (-1240 3810);
PAINT MONO (-1240 3810);
FORCEPROP 0 LASTPIN (-1250 3850) $PN CT32
J 0
(-1240 3860);
DISPLAY 0.489362 (-1240 3860);
PAINT MONO (-1240 3860);
FORCEPROP 0 LASTPIN (-1250 3900) $PN CT33
J 0
(-1240 3910);
DISPLAY 0.489362 (-1240 3910);
PAINT MONO (-1240 3910);
FORCEPROP 0 LASTPIN (-1250 3950) $PN CT34
J 0
(-1240 3960);
DISPLAY 0.489362 (-1240 3960);
PAINT MONO (-1240 3960);
FORCEPROP 0 LASTPIN (-1250 4000) $PN CT37
J 0
(-1240 4010);
DISPLAY 0.489362 (-1240 4010);
PAINT MONO (-1240 4010);
FORCEPROP 0 LASTPIN (-1250 4050) $PN CT39
J 0
(-1240 4060);
DISPLAY 0.489362 (-1240 4060);
PAINT MONO (-1240 4060);
FORCEPROP 0 LASTPIN (-1250 4100) $PN CT42
J 0
(-1240 4110);
DISPLAY 0.489362 (-1240 4110);
PAINT MONO (-1240 4110);
FORCEPROP 0 LASTPIN (-1250 4150) $PN CT43
J 0
(-1240 4160);
DISPLAY 0.489362 (-1240 4160);
PAINT MONO (-1240 4160);
FORCEPROP 0 LASTPIN (-1250 4200) $PN CT44
J 0
(-1240 4210);
DISPLAY 0.489362 (-1240 4210);
PAINT MONO (-1240 4210);
FORCEPROP 0 LASTPIN (-1250 4250) $PN CT45
J 0
(-1240 4260);
DISPLAY 0.489362 (-1240 4260);
PAINT MONO (-1240 4260);
FORCEPROP 0 LASTPIN (-1250 4300) $PN CT46
J 0
(-1240 4310);
DISPLAY 0.489362 (-1240 4310);
PAINT MONO (-1240 4310);
FORCEPROP 0 LASTPIN (-1250 4350) $PN CT47
J 0
(-1240 4360);
DISPLAY 0.489362 (-1240 4360);
PAINT MONO (-1240 4360);
FORCEPROP 0 LASTPIN (-1250 4400) $PN CT48
J 0
(-1240 4410);
DISPLAY 0.489362 (-1240 4410);
PAINT MONO (-1240 4410);
FORCEPROP 0 LASTPIN (-1250 4450) $PN CT49
J 0
(-1240 4460);
DISPLAY 0.489362 (-1240 4460);
PAINT MONO (-1240 4460);
FORCEPROP 0 LASTPIN (-1250 4500) $PN CT50
J 0
(-1240 4510);
DISPLAY 0.489362 (-1240 4510);
PAINT MONO (-1240 4510);
FORCEPROP 0 LASTPIN (-1250 4550) $PN CT51
J 0
(-1240 4560);
DISPLAY 0.489362 (-1240 4560);
PAINT MONO (-1240 4560);
FORCEPROP 0 LASTPIN (-1250 4600) $PN CT53
J 0
(-1240 4610);
DISPLAY 0.489362 (-1240 4610);
PAINT MONO (-1240 4610);
FORCEPROP 0 LASTPIN (-1250 4650) $PN CT59
J 0
(-1240 4660);
DISPLAY 0.489362 (-1240 4660);
PAINT MONO (-1240 4660);
FORCEPROP 0 LASTPIN (-1250 4700) $PN CT61
J 0
(-1240 4710);
DISPLAY 0.489362 (-1240 4710);
PAINT MONO (-1240 4710);
FORCEPROP 0 LASTPIN (-1250 4750) $PN CT66
J 0
(-1240 4760);
DISPLAY 0.489362 (-1240 4760);
PAINT MONO (-1240 4760);
FORCEPROP 0 LASTPIN (-1250 4800) $PN CT68
J 0
(-1240 4810);
DISPLAY 0.489362 (-1240 4810);
PAINT MONO (-1240 4810);
FORCEPROP 0 LASTPIN (-1250 4850) $PN CT73
J 0
(-1240 4860);
DISPLAY 0.489362 (-1240 4860);
PAINT MONO (-1240 4860);
FORCEPROP 0 LASTPIN (-1250 4900) $PN CU1
J 0
(-1240 4910);
DISPLAY 0.489362 (-1240 4910);
PAINT MONO (-1240 4910);
FORCEPROP 0 LASTPIN (-1250 4950) $PN CU4
J 0
(-1240 4960);
DISPLAY 0.489362 (-1240 4960);
PAINT MONO (-1240 4960);
FORCEPROP 0 LASTPIN (-1250 5000) $PN CU6
J 0
(-1240 5010);
DISPLAY 0.489362 (-1240 5010);
PAINT MONO (-1240 5010);
FORCEPROP 0 LASTPIN (-1250 5050) $PN CU8
J 0
(-1240 5060);
DISPLAY 0.489362 (-1240 5060);
PAINT MONO (-1240 5060);
FORCEPROP 0 LASTPIN (-1250 5100) $PN CU11
J 0
(-1240 5110);
DISPLAY 0.489362 (-1240 5110);
PAINT MONO (-1240 5110);
FORCEPROP 0 LASTPIN (-1250 5150) $PN CU13
J 0
(-1240 5160);
DISPLAY 0.489362 (-1240 5160);
PAINT MONO (-1240 5160);
FORCEPROP 0 LASTPIN (-1250 5200) $PN CU15
J 0
(-1240 5210);
DISPLAY 0.489362 (-1240 5210);
PAINT MONO (-1240 5210);
FORCEPROP 0 LASTPIN (-1250 5250) $PN CU18
J 0
(-1240 5260);
DISPLAY 0.489362 (-1240 5260);
PAINT MONO (-1240 5260);
FORCEPROP 0 LASTPIN (-1250 5300) $PN CU20
J 0
(-1240 5310);
DISPLAY 0.489362 (-1240 5310);
PAINT MONO (-1240 5310);
FORCEPROP 0 LASTPIN (-1250 5350) $PN CU22
J 0
(-1240 5360);
DISPLAY 0.489362 (-1240 5360);
PAINT MONO (-1240 5360);
FORCEPROP 0 LASTPIN (-1250 5400) $PN CU25
J 0
(-1240 5410);
DISPLAY 0.489362 (-1240 5410);
PAINT MONO (-1240 5410);
FORCEPROP 0 LASTPIN (-1250 5450) $PN CU28
J 0
(-1240 5460);
DISPLAY 0.489362 (-1240 5460);
PAINT MONO (-1240 5460);
FORCEPROP 0 LASTPIN (-1250 5500) $PN CU31
J 0
(-1240 5510);
DISPLAY 0.489362 (-1240 5510);
PAINT MONO (-1240 5510);
FORCEPROP 0 LASTPIN (-1250 5550) $PN CU34
J 0
(-1240 5560);
DISPLAY 0.489362 (-1240 5560);
PAINT MONO (-1240 5560);
FORCEPROP 0 LASTPIN (-1250 5600) $PN CU42
J 0
(-1240 5610);
DISPLAY 0.489362 (-1240 5610);
PAINT MONO (-1240 5610);
FORCEPROP 0 LASTPIN (-1250 5650) $PN CU45
J 0
(-1240 5660);
DISPLAY 0.489362 (-1240 5660);
PAINT MONO (-1240 5660);
FORCEPROP 0 LASTPIN (-1250 5700) $PN CU48
J 0
(-1240 5710);
DISPLAY 0.489362 (-1240 5710);
PAINT MONO (-1240 5710);
FORCEPROP 0 LASTPIN (-1250 5750) $PN CU51
J 0
(-1240 5760);
DISPLAY 0.489362 (-1240 5760);
PAINT MONO (-1240 5760);
FORCEPROP 0 LASTPIN (-1250 5800) $PN CU54
J 0
(-1240 5810);
DISPLAY 0.489362 (-1240 5810);
PAINT MONO (-1240 5810);
FORCEPROP 0 LASTPIN (-1250 5850) $PN CU56
J 0
(-1240 5860);
DISPLAY 0.489362 (-1240 5860);
PAINT MONO (-1240 5860);
FORCEPROP 0 LASTPIN (-1250 5900) $PN CU61
J 0
(-1240 5910);
DISPLAY 0.489362 (-1240 5910);
PAINT MONO (-1240 5910);
FORCEPROP 0 LASTPIN (-1250 5950) $PN CU63
J 0
(-1240 5960);
DISPLAY 0.489362 (-1240 5960);
PAINT MONO (-1240 5960);
FORCEPROP 0 LASTPIN (-1250 6000) $PN CU65
J 0
(-1240 6010);
DISPLAY 0.489362 (-1240 6010);
PAINT MONO (-1240 6010);
FORCEPROP 0 LASTPIN (-1250 6050) $PN CU68
J 0
(-1240 6060);
DISPLAY 0.489362 (-1240 6060);
PAINT MONO (-1240 6060);
FORCEPROP 0 LASTPIN (-1250 6100) $PN CU70
J 0
(-1240 6110);
DISPLAY 0.489362 (-1240 6110);
PAINT MONO (-1240 6110);
FORCEPROP 0 LASTPIN (-1250 6150) $PN CU72
J 0
(-1240 6160);
DISPLAY 0.489362 (-1240 6160);
PAINT MONO (-1240 6160);
FORCEPROP 0 LASTPIN (-1250 6200) $PN CU75
J 0
(-1240 6210);
DISPLAY 0.489362 (-1240 6210);
PAINT MONO (-1240 6210);
FORCEPROP 0 LASTPIN (-1250 6250) $PN CV3
J 0
(-1240 6260);
DISPLAY 0.489362 (-1240 6260);
PAINT MONO (-1240 6260);
FORCEPROP 0 LASTPIN (-1250 6300) $PN CV5
J 0
(-1240 6310);
DISPLAY 0.489362 (-1240 6310);
PAINT MONO (-1240 6310);
FORCEPROP 0 LASTPIN (-1250 6350) $PN CV8
J 0
(-1240 6360);
DISPLAY 0.489362 (-1240 6360);
PAINT MONO (-1240 6360);
FORCEPROP 0 LASTPIN (-2350 550) $PN CV10
J 2
(-2360 560);
DISPLAY 0.489362 (-2360 560);
PAINT MONO (-2360 560);
FORCEPROP 0 LASTPIN (-2350 600) $PN CV12
J 2
(-2360 610);
DISPLAY 0.489362 (-2360 610);
PAINT MONO (-2360 610);
FORCEPROP 0 LASTPIN (-2350 650) $PN CV15
J 2
(-2360 660);
DISPLAY 0.489362 (-2360 660);
PAINT MONO (-2360 660);
FORCEPROP 0 LASTPIN (-2350 700) $PN CV17
J 2
(-2360 710);
DISPLAY 0.489362 (-2360 710);
PAINT MONO (-2360 710);
FORCEPROP 0 LASTPIN (-2350 750) $PN CV19
J 2
(-2360 760);
DISPLAY 0.489362 (-2360 760);
PAINT MONO (-2360 760);
FORCEPROP 0 LASTPIN (-2350 800) $PN CV22
J 2
(-2360 810);
DISPLAY 0.489362 (-2360 810);
PAINT MONO (-2360 810);
FORCEPROP 0 LASTPIN (-2350 850) $PN CV25
J 2
(-2360 860);
DISPLAY 0.489362 (-2360 860);
PAINT MONO (-2360 860);
FORCEPROP 0 LASTPIN (-2350 900) $PN CV28
J 2
(-2360 910);
DISPLAY 0.489362 (-2360 910);
PAINT MONO (-2360 910);
FORCEPROP 0 LASTPIN (-2350 950) $PN CV31
J 2
(-2360 960);
DISPLAY 0.489362 (-2360 960);
PAINT MONO (-2360 960);
FORCEPROP 0 LASTPIN (-2350 1000) $PN CV34
J 2
(-2360 1010);
DISPLAY 0.489362 (-2360 1010);
PAINT MONO (-2360 1010);
FORCEPROP 0 LASTPIN (-2350 1050) $PN CV37
J 2
(-2360 1060);
DISPLAY 0.489362 (-2360 1060);
PAINT MONO (-2360 1060);
FORCEPROP 0 LASTPIN (-2350 1100) $PN CV39
J 2
(-2360 1110);
DISPLAY 0.489362 (-2360 1110);
PAINT MONO (-2360 1110);
FORCEPROP 0 LASTPIN (-2350 1150) $PN CV42
J 2
(-2360 1160);
DISPLAY 0.489362 (-2360 1160);
PAINT MONO (-2360 1160);
FORCEPROP 0 LASTPIN (-2350 1200) $PN CV45
J 2
(-2360 1210);
DISPLAY 0.489362 (-2360 1210);
PAINT MONO (-2360 1210);
FORCEPROP 0 LASTPIN (-2350 1250) $PN CV48
J 2
(-2360 1260);
DISPLAY 0.489362 (-2360 1260);
PAINT MONO (-2360 1260);
FORCEPROP 0 LASTPIN (-2350 1300) $PN CV51
J 2
(-2360 1310);
DISPLAY 0.489362 (-2360 1310);
PAINT MONO (-2360 1310);
FORCEPROP 0 LASTPIN (-2350 1350) $PN CV54
J 2
(-2360 1360);
DISPLAY 0.489362 (-2360 1360);
PAINT MONO (-2360 1360);
FORCEPROP 0 LASTPIN (-2350 1400) $PN CV57
J 2
(-2360 1410);
DISPLAY 0.489362 (-2360 1410);
PAINT MONO (-2360 1410);
FORCEPROP 0 LASTPIN (-2350 1450) $PN CV59
J 2
(-2360 1460);
DISPLAY 0.489362 (-2360 1460);
PAINT MONO (-2360 1460);
FORCEPROP 0 LASTPIN (-2350 1500) $PN CV61
J 2
(-2360 1510);
DISPLAY 0.489362 (-2360 1510);
PAINT MONO (-2360 1510);
FORCEPROP 0 LASTPIN (-2350 1550) $PN CV64
J 2
(-2360 1560);
DISPLAY 0.489362 (-2360 1560);
PAINT MONO (-2360 1560);
FORCEPROP 0 LASTPIN (-2350 1600) $PN CV66
J 2
(-2360 1610);
DISPLAY 0.489362 (-2360 1610);
PAINT MONO (-2360 1610);
FORCEPROP 0 LASTPIN (-2350 1650) $PN CV68
J 2
(-2360 1660);
DISPLAY 0.489362 (-2360 1660);
PAINT MONO (-2360 1660);
FORCEPROP 0 LASTPIN (-2350 1700) $PN CV71
J 2
(-2360 1710);
DISPLAY 0.489362 (-2360 1710);
PAINT MONO (-2360 1710);
FORCEPROP 0 LASTPIN (-2350 1750) $PN CV73
J 2
(-2360 1760);
DISPLAY 0.489362 (-2360 1760);
PAINT MONO (-2360 1760);
FORCEPROP 0 LASTPIN (-2350 1800) $PN CW1
J 2
(-2360 1810);
DISPLAY 0.489362 (-2360 1810);
PAINT MONO (-2360 1810);
FORCEPROP 0 LASTPIN (-2350 1850) $PN CW6
J 2
(-2360 1860);
DISPLAY 0.489362 (-2360 1860);
PAINT MONO (-2360 1860);
FORCEPROP 0 LASTPIN (-2350 1900) $PN CW8
J 2
(-2360 1910);
DISPLAY 0.489362 (-2360 1910);
PAINT MONO (-2360 1910);
FORCEPROP 0 LASTPIN (-2350 1950) $PN CW13
J 2
(-2360 1960);
DISPLAY 0.489362 (-2360 1960);
PAINT MONO (-2360 1960);
FORCEPROP 0 LASTPIN (-2350 2000) $PN CW15
J 2
(-2360 2010);
DISPLAY 0.489362 (-2360 2010);
PAINT MONO (-2360 2010);
FORCEPROP 0 LASTPIN (-2350 2050) $PN CW20
J 2
(-2360 2060);
DISPLAY 0.489362 (-2360 2060);
PAINT MONO (-2360 2060);
FORCEPROP 0 LASTPIN (-2350 2100) $PN CW22
J 2
(-2360 2110);
DISPLAY 0.489362 (-2360 2110);
PAINT MONO (-2360 2110);
FORCEPROP 0 LASTPIN (-2350 2150) $PN CW25
J 2
(-2360 2160);
DISPLAY 0.489362 (-2360 2160);
PAINT MONO (-2360 2160);
FORCEPROP 0 LASTPIN (-2350 2200) $PN CW28
J 2
(-2360 2210);
DISPLAY 0.489362 (-2360 2210);
PAINT MONO (-2360 2210);
FORCEPROP 0 LASTPIN (-2350 2250) $PN CW31
J 2
(-2360 2260);
DISPLAY 0.489362 (-2360 2260);
PAINT MONO (-2360 2260);
FORCEPROP 0 LASTPIN (-2350 2300) $PN CW34
J 2
(-2360 2310);
DISPLAY 0.489362 (-2360 2310);
PAINT MONO (-2360 2310);
FORCEPROP 0 LASTPIN (-2350 2350) $PN CW35
J 2
(-2360 2360);
DISPLAY 0.489362 (-2360 2360);
PAINT MONO (-2360 2360);
FORCEPROP 0 LASTPIN (-2350 2400) $PN CW36
J 2
(-2360 2410);
DISPLAY 0.489362 (-2360 2410);
PAINT MONO (-2360 2410);
FORCEPROP 0 LASTPIN (-2350 2450) $PN CW40
J 2
(-2360 2460);
DISPLAY 0.489362 (-2360 2460);
PAINT MONO (-2360 2460);
FORCEPROP 0 LASTPIN (-2350 2500) $PN CW41
J 2
(-2360 2510);
DISPLAY 0.489362 (-2360 2510);
PAINT MONO (-2360 2510);
FORCEPROP 0 LASTPIN (-2350 2550) $PN CW42
J 2
(-2360 2560);
DISPLAY 0.489362 (-2360 2560);
PAINT MONO (-2360 2560);
FORCEPROP 0 LASTPIN (-2350 2600) $PN CW45
J 2
(-2360 2610);
DISPLAY 0.489362 (-2360 2610);
PAINT MONO (-2360 2610);
FORCEPROP 0 LASTPIN (-2350 2650) $PN CW48
J 2
(-2360 2660);
DISPLAY 0.489362 (-2360 2660);
PAINT MONO (-2360 2660);
FORCEPROP 0 LASTPIN (-2350 2700) $PN CW51
J 2
(-2360 2710);
DISPLAY 0.489362 (-2360 2710);
PAINT MONO (-2360 2710);
FORCEPROP 0 LASTPIN (-2350 2750) $PN CW54
J 2
(-2360 2760);
DISPLAY 0.489362 (-2360 2760);
PAINT MONO (-2360 2760);
FORCEPROP 0 LASTPIN (-2350 2800) $PN CW56
J 2
(-2360 2810);
DISPLAY 0.489362 (-2360 2810);
PAINT MONO (-2360 2810);
FORCEPROP 0 LASTPIN (-2350 2850) $PN CW61
J 2
(-2360 2860);
DISPLAY 0.489362 (-2360 2860);
PAINT MONO (-2360 2860);
FORCEPROP 0 LASTPIN (-2350 2900) $PN CW63
J 2
(-2360 2910);
DISPLAY 0.489362 (-2360 2910);
PAINT MONO (-2360 2910);
FORCEPROP 0 LASTPIN (-2350 2950) $PN CW68
J 2
(-2360 2960);
DISPLAY 0.489362 (-2360 2960);
PAINT MONO (-2360 2960);
FORCEPROP 0 LASTPIN (-2350 3000) $PN CW70
J 2
(-2360 3010);
DISPLAY 0.489362 (-2360 3010);
PAINT MONO (-2360 3010);
FORCEPROP 0 LASTPIN (-2350 3050) $PN CW75
J 2
(-2360 3060);
DISPLAY 0.489362 (-2360 3060);
PAINT MONO (-2360 3060);
FORCEPROP 0 LASTPIN (-2350 3100) $PN CY3
J 2
(-2360 3110);
DISPLAY 0.489362 (-2360 3110);
PAINT MONO (-2360 3110);
FORCEPROP 0 LASTPIN (-2350 3150) $PN CY5
J 2
(-2360 3160);
DISPLAY 0.489362 (-2360 3160);
PAINT MONO (-2360 3160);
FORCEPROP 0 LASTPIN (-2350 3200) $PN CY8
J 2
(-2360 3210);
DISPLAY 0.489362 (-2360 3210);
PAINT MONO (-2360 3210);
FORCEPROP 0 LASTPIN (-2350 3250) $PN CY10
J 2
(-2360 3260);
DISPLAY 0.489362 (-2360 3260);
PAINT MONO (-2360 3260);
FORCEPROP 0 LASTPIN (-2350 3300) $PN CY12
J 2
(-2360 3310);
DISPLAY 0.489362 (-2360 3310);
PAINT MONO (-2360 3310);
FORCEPROP 0 LASTPIN (-2350 3350) $PN CY15
J 2
(-2360 3360);
DISPLAY 0.489362 (-2360 3360);
PAINT MONO (-2360 3360);
FORCEPROP 0 LASTPIN (-2350 3400) $PN CY17
J 2
(-2360 3410);
DISPLAY 0.489362 (-2360 3410);
PAINT MONO (-2360 3410);
FORCEPROP 0 LASTPIN (-2350 3450) $PN CY19
J 2
(-2360 3460);
DISPLAY 0.489362 (-2360 3460);
PAINT MONO (-2360 3460);
FORCEPROP 0 LASTPIN (-2350 3500) $PN CY23
J 2
(-2360 3510);
DISPLAY 0.489362 (-2360 3510);
PAINT MONO (-2360 3510);
FORCEPROP 0 LASTPIN (-2350 3550) $PN CY24
J 2
(-2360 3560);
DISPLAY 0.489362 (-2360 3560);
PAINT MONO (-2360 3560);
FORCEPROP 0 LASTPIN (-2350 3600) $PN CY25
J 2
(-2360 3610);
DISPLAY 0.489362 (-2360 3610);
PAINT MONO (-2360 3610);
FORCEPROP 0 LASTPIN (-2350 3650) $PN CY26
J 2
(-2360 3660);
DISPLAY 0.489362 (-2360 3660);
PAINT MONO (-2360 3660);
FORCEPROP 0 LASTPIN (-2350 3700) $PN CY27
J 2
(-2360 3710);
DISPLAY 0.489362 (-2360 3710);
PAINT MONO (-2360 3710);
FORCEPROP 0 LASTPIN (-2350 3750) $PN CY28
J 2
(-2360 3760);
DISPLAY 0.489362 (-2360 3760);
PAINT MONO (-2360 3760);
FORCEPROP 0 LASTPIN (-2350 3800) $PN CY29
J 2
(-2360 3810);
DISPLAY 0.489362 (-2360 3810);
PAINT MONO (-2360 3810);
FORCEPROP 0 LASTPIN (-2350 3850) $PN CY30
J 2
(-2360 3860);
DISPLAY 0.489362 (-2360 3860);
PAINT MONO (-2360 3860);
FORCEPROP 0 LASTPIN (-2350 3900) $PN CY31
J 2
(-2360 3910);
DISPLAY 0.489362 (-2360 3910);
PAINT MONO (-2360 3910);
FORCEPROP 0 LASTPIN (-2350 3950) $PN CY32
J 2
(-2360 3960);
DISPLAY 0.489362 (-2360 3960);
PAINT MONO (-2360 3960);
FORCEPROP 0 LASTPIN (-2350 4000) $PN CY33
J 2
(-2360 4010);
DISPLAY 0.489362 (-2360 4010);
PAINT MONO (-2360 4010);
FORCEPROP 0 LASTPIN (-2350 4050) $PN CY34
J 2
(-2360 4060);
DISPLAY 0.489362 (-2360 4060);
PAINT MONO (-2360 4060);
FORCEPROP 0 LASTPIN (-2350 4100) $PN CY37
J 2
(-2360 4110);
DISPLAY 0.489362 (-2360 4110);
PAINT MONO (-2360 4110);
FORCEPROP 0 LASTPIN (-2350 4150) $PN CY39
J 2
(-2360 4160);
DISPLAY 0.489362 (-2360 4160);
PAINT MONO (-2360 4160);
FORCEPROP 0 LASTPIN (-2350 4200) $PN CY42
J 2
(-2360 4210);
DISPLAY 0.489362 (-2360 4210);
PAINT MONO (-2360 4210);
FORCEPROP 0 LASTPIN (-2350 4250) $PN CY43
J 2
(-2360 4260);
DISPLAY 0.489362 (-2360 4260);
PAINT MONO (-2360 4260);
FORCEPROP 0 LASTPIN (-2350 4300) $PN CY44
J 2
(-2360 4310);
DISPLAY 0.489362 (-2360 4310);
PAINT MONO (-2360 4310);
FORCEPROP 0 LASTPIN (-2350 4350) $PN CY45
J 2
(-2360 4360);
DISPLAY 0.489362 (-2360 4360);
PAINT MONO (-2360 4360);
FORCEPROP 0 LASTPIN (-2350 4400) $PN CY46
J 2
(-2360 4410);
DISPLAY 0.489362 (-2360 4410);
PAINT MONO (-2360 4410);
FORCEPROP 0 LASTPIN (-2350 4450) $PN CY47
J 2
(-2360 4460);
DISPLAY 0.489362 (-2360 4460);
PAINT MONO (-2360 4460);
FORCEPROP 0 LASTPIN (-2350 4500) $PN CY48
J 2
(-2360 4510);
DISPLAY 0.489362 (-2360 4510);
PAINT MONO (-2360 4510);
FORCEPROP 0 LASTPIN (-2350 4550) $PN CY49
J 2
(-2360 4560);
DISPLAY 0.489362 (-2360 4560);
PAINT MONO (-2360 4560);
FORCEPROP 0 LASTPIN (-2350 4600) $PN CY50
J 2
(-2360 4610);
DISPLAY 0.489362 (-2360 4610);
PAINT MONO (-2360 4610);
FORCEPROP 0 LASTPIN (-2350 4650) $PN CY51
J 2
(-2360 4660);
DISPLAY 0.489362 (-2360 4660);
PAINT MONO (-2360 4660);
FORCEPROP 0 LASTPIN (-2350 4700) $PN CY52
J 2
(-2360 4710);
DISPLAY 0.489362 (-2360 4710);
PAINT MONO (-2360 4710);
FORCEPROP 0 LASTPIN (-2350 4750) $PN CY53
J 2
(-2360 4760);
DISPLAY 0.489362 (-2360 4760);
PAINT MONO (-2360 4760);
FORCEPROP 0 LASTPIN (-2350 4800) $PN CY59
J 2
(-2360 4810);
DISPLAY 0.489362 (-2360 4810);
PAINT MONO (-2360 4810);
FORCEPROP 0 LASTPIN (-2350 4850) $PN CY61
J 2
(-2360 4860);
DISPLAY 0.489362 (-2360 4860);
PAINT MONO (-2360 4860);
FORCEPROP 0 LASTPIN (-2350 4900) $PN CY64
J 2
(-2360 4910);
DISPLAY 0.489362 (-2360 4910);
PAINT MONO (-2360 4910);
FORCEPROP 0 LASTPIN (-2350 4950) $PN CY66
J 2
(-2360 4960);
DISPLAY 0.489362 (-2360 4960);
PAINT MONO (-2360 4960);
FORCEPROP 0 LASTPIN (-2350 5000) $PN CY68
J 2
(-2360 5010);
DISPLAY 0.489362 (-2360 5010);
PAINT MONO (-2360 5010);
FORCEPROP 0 LASTPIN (-2350 5050) $PN CY71
J 2
(-2360 5060);
DISPLAY 0.489362 (-2360 5060);
PAINT MONO (-2360 5060);
FORCEPROP 0 LASTPIN (-2350 5100) $PN CY73
J 2
(-2360 5110);
DISPLAY 0.489362 (-2360 5110);
PAINT MONO (-2360 5110);
FORCEPROP 0 LASTPIN (-2350 5150) $PN DA1
J 2
(-2360 5160);
DISPLAY 0.489362 (-2360 5160);
PAINT MONO (-2360 5160);
FORCEPROP 0 LASTPIN (-2350 5200) $PN DA4
J 2
(-2360 5210);
DISPLAY 0.489362 (-2360 5210);
PAINT MONO (-2360 5210);
FORCEPROP 0 LASTPIN (-2350 5250) $PN DA6
J 2
(-2360 5260);
DISPLAY 0.489362 (-2360 5260);
PAINT MONO (-2360 5260);
FORCEPROP 0 LASTPIN (-2350 5300) $PN DA8
J 2
(-2360 5310);
DISPLAY 0.489362 (-2360 5310);
PAINT MONO (-2360 5310);
FORCEPROP 0 LASTPIN (-2350 5350) $PN DA11
J 2
(-2360 5360);
DISPLAY 0.489362 (-2360 5360);
PAINT MONO (-2360 5360);
FORCEPROP 0 LASTPIN (-2350 5400) $PN DA13
J 2
(-2360 5410);
DISPLAY 0.489362 (-2360 5410);
PAINT MONO (-2360 5410);
FORCEPROP 0 LASTPIN (-2350 5450) $PN DA15
J 2
(-2360 5460);
DISPLAY 0.489362 (-2360 5460);
PAINT MONO (-2360 5460);
FORCEPROP 0 LASTPIN (-2350 5500) $PN DA18
J 2
(-2360 5510);
DISPLAY 0.489362 (-2360 5510);
PAINT MONO (-2360 5510);
FORCEPROP 0 LASTPIN (-2350 5550) $PN DA20
J 2
(-2360 5560);
DISPLAY 0.489362 (-2360 5560);
PAINT MONO (-2360 5560);
FORCEPROP 0 LASTPIN (-2350 5600) $PN DA22
J 2
(-2360 5610);
DISPLAY 0.489362 (-2360 5610);
PAINT MONO (-2360 5610);
FORCEPROP 0 LASTPIN (-2350 5650) $PN DA25
J 2
(-2360 5660);
DISPLAY 0.489362 (-2360 5660);
PAINT MONO (-2360 5660);
FORCEPROP 0 LASTPIN (-2350 5700) $PN DA28
J 2
(-2360 5710);
DISPLAY 0.489362 (-2360 5710);
PAINT MONO (-2360 5710);
FORCEPROP 0 LASTPIN (-2350 5750) $PN DA31
J 2
(-2360 5760);
DISPLAY 0.489362 (-2360 5760);
PAINT MONO (-2360 5760);
FORCEPROP 0 LASTPIN (-2350 5800) $PN DA34
J 2
(-2360 5810);
DISPLAY 0.489362 (-2360 5810);
PAINT MONO (-2360 5810);
FORCEPROP 0 LASTPIN (-2350 5850) $PN DA42
J 2
(-2360 5860);
DISPLAY 0.489362 (-2360 5860);
PAINT MONO (-2360 5860);
FORCEPROP 0 LASTPIN (-2350 5900) $PN DA45
J 2
(-2360 5910);
DISPLAY 0.489362 (-2360 5910);
PAINT MONO (-2360 5910);
FORCEPROP 0 LASTPIN (-2350 5950) $PN DA48
J 2
(-2360 5960);
DISPLAY 0.489362 (-2360 5960);
PAINT MONO (-2360 5960);
FORCEPROP 0 LASTPIN (-2350 6000) $PN DA51
J 2
(-2360 6010);
DISPLAY 0.489362 (-2360 6010);
PAINT MONO (-2360 6010);
FORCEPROP 0 LASTPIN (-2350 6050) $PN DA54
J 2
(-2360 6060);
DISPLAY 0.489362 (-2360 6060);
PAINT MONO (-2360 6060);
FORCEPROP 0 LASTPIN (-2350 6100) $PN DA58
J 2
(-2360 6110);
DISPLAY 0.489362 (-2360 6110);
PAINT MONO (-2360 6110);
FORCEPROP 0 LASTPIN (-2350 6150) $PN DA61
J 2
(-2360 6160);
DISPLAY 0.489362 (-2360 6160);
PAINT MONO (-2360 6160);
FORCEPROP 0 LASTPIN (-2350 6200) $PN DA63
J 2
(-2360 6210);
DISPLAY 0.489362 (-2360 6210);
PAINT MONO (-2360 6210);
FORCEPROP 0 LASTPIN (-2350 6250) $PN DA65
J 2
(-2360 6260);
DISPLAY 0.489362 (-2360 6260);
PAINT MONO (-2360 6260);
FORCEPROP 0 LASTPIN (-2350 6300) $PN DA68
J 2
(-2360 6310);
DISPLAY 0.489362 (-2360 6310);
PAINT MONO (-2360 6310);
FORCEPROP 0 LASTPIN (-2350 6350) $PN DA70
J 2
(-2360 6360);
DISPLAY 0.489362 (-2360 6360);
PAINT MONO (-2360 6360);
FORCEPROP 2 LAST PART_TYPE SMLF
J 0
(-2425 6700);
DISPLAY 1.021277 (-2425 6700);
FORCEPROP 1 LAST MATERIAL IO
J 0
(-2195 6582);
DISPLAY 0.489362 (-2195 6582);
PAINT SKYBLUE (-2195 6582);
FORCEPROP 2 LAST VALUE SOCKET6096_13568-001
J 0
(-2200 6625);
DISPLAY 0.489362 (-2200 6625);
PAINT SKYBLUE (-2200 6625);
FORCEPROP 2 LAST CDS_LIB pure_quanta
J 0
(-1800 3500);
DISPLAY INVISIBLE (-1800 3500);
FORCEPROP 1 LAST CDS_LMAN_SYM_OUTLINE -400,3050,400,-3050
J 0
(-1800 3500);
DISPLAY 0.468085 (-1800 3500);
PAINT GREEN (-1800 3500);
DISPLAY INVISIBLE (-1800 3500);
FORCEPROP 1 LAST NEEDS_NO_SIZE TRUE
J 0
(-1800 3500);
DISPLAY 0.723404 (-1800 3500);
PAINT GREEN (-1800 3500);
DISPLAY INVISIBLE (-1800 3500);
FORCEPROP 1 LAST PATH I4
J 0
(-1800 3500);
DISPLAY 0.723404 (-1800 3500);
PAINT GREEN (-1800 3500);
DISPLAY INVISIBLE (-1800 3500);
FORCEPROP 1 LAST PART_NUMBER DGA^6000030
J 0
(-2195 6709);
DISPLAY 0.489362 (-2195 6709);
PAINT SKYBLUE (-2195 6709);
DISPLAY INVISIBLE (-2195 6709);
FORCEADD UNIVERSAL_GND..1
(-1075 450);
FORCEPROP 3 LASTPIN (-1075 500) SIG_NAME GND\g
J 0
(-1065 510);
DISPLAY 0.659574 (-1065 510);
PAINT MONO (-1065 510);
DISPLAY INVISIBLE (-1065 510);
FORCEPROP 2 LAST CDS_LIB pure_quanta_power
J 0
(-1075 450);
DISPLAY INVISIBLE (-1075 450);
FORCEPROP 1 LAST HDL_POWER GND
J 1
(-1050 375);
DISPLAY 0.872340 (-1050 375);
PAINT GREEN (-1050 375);
DISPLAY INVISIBLE (-1050 375);
FORCEPROP 1 LAST PATH I5
J 0
(-1000 450);
DISPLAY 0.872340 (-1000 450);
PAINT AQUA (-1000 450);
DISPLAY INVISIBLE (-1000 450);
FORCEADD UNIVERSAL_GND..1
(-2525 450);
FORCEPROP 3 LASTPIN (-2525 500) SIG_NAME GND\g
J 0
(-2515 510);
DISPLAY 0.659574 (-2515 510);
PAINT MONO (-2515 510);
DISPLAY INVISIBLE (-2515 510);
FORCEPROP 2 LAST CDS_LIB pure_quanta_power
J 0
(-2525 450);
DISPLAY INVISIBLE (-2525 450);
FORCEPROP 1 LAST HDL_POWER GND
J 1
(-2500 375);
DISPLAY 0.872340 (-2500 375);
PAINT GREEN (-2500 375);
DISPLAY INVISIBLE (-2500 375);
FORCEPROP 1 LAST PATH I6
J 0
(-2450 450);
DISPLAY 0.872340 (-2450 450);
PAINT AQUA (-2450 450);
DISPLAY INVISIBLE (-2450 450);
FORCEADD UNIVERSAL_GND..1
(-3150 450);
FORCEPROP 3 LASTPIN (-3150 500) SIG_NAME GND\g
J 0
(-3140 510);
DISPLAY 0.659574 (-3140 510);
PAINT MONO (-3140 510);
DISPLAY INVISIBLE (-3140 510);
FORCEPROP 2 LAST CDS_LIB pure_quanta_power
J 0
(-3150 450);
DISPLAY INVISIBLE (-3150 450);
FORCEPROP 1 LAST HDL_POWER GND
J 1
(-3125 375);
DISPLAY 0.872340 (-3125 375);
PAINT GREEN (-3125 375);
DISPLAY INVISIBLE (-3125 375);
FORCEPROP 1 LAST PATH I7
J 0
(-3075 450);
DISPLAY 0.872340 (-3075 450);
PAINT AQUA (-3075 450);
DISPLAY INVISIBLE (-3075 450);
FORCEADD UNIVERSAL_GND..1
(-4600 475);
FORCEPROP 3 LASTPIN (-4600 525) SIG_NAME GND\g
J 0
(-4590 535);
DISPLAY 0.659574 (-4590 535);
PAINT MONO (-4590 535);
DISPLAY INVISIBLE (-4590 535);
FORCEPROP 2 LAST CDS_LIB pure_quanta_power
J 0
(-4600 475);
DISPLAY INVISIBLE (-4600 475);
FORCEPROP 1 LAST HDL_POWER GND
J 1
(-4575 400);
DISPLAY 0.872340 (-4575 400);
PAINT GREEN (-4575 400);
DISPLAY INVISIBLE (-4575 400);
FORCEPROP 1 LAST PATH I8
J 0
(-4525 475);
DISPLAY 0.872340 (-4525 475);
PAINT AQUA (-4525 475);
DISPLAY INVISIBLE (-4525 475);
FORCEADD UNIVERSAL_GND..1
(-5225 475);
FORCEPROP 3 LASTPIN (-5225 525) SIG_NAME GND\g
J 0
(-5215 535);
DISPLAY 0.659574 (-5215 535);
PAINT MONO (-5215 535);
DISPLAY INVISIBLE (-5215 535);
FORCEPROP 2 LAST CDS_LIB pure_quanta_power
J 0
(-5225 475);
DISPLAY INVISIBLE (-5225 475);
FORCEPROP 1 LAST HDL_POWER GND
J 1
(-5200 400);
DISPLAY 0.872340 (-5200 400);
PAINT GREEN (-5200 400);
DISPLAY INVISIBLE (-5200 400);
FORCEPROP 1 LAST PATH I9
J 0
(-5150 475);
DISPLAY 0.872340 (-5150 475);
PAINT AQUA (-5150 475);
DISPLAY INVISIBLE (-5150 475);
FORCEADD QUANTA_TITLE_BLOCK_C..1
(-100 100);
FORCEPROP 0 LAST CDS_CON_LAST_MODIFIED Thu Sep 14 16:12:02 2023
J 0
(-1985 115);
DISPLAY INVISIBLE (-1985 115);
FORCEPROP 1 LAST CUSTOM_TXT_CDS <CON_LAST_MODIFIED>
J 0
(-1985 115);
DISPLAY 0.978723 (-1985 115);
FORCEPROP 2 LAST CUSTOM_TXT_CDS <XR_PAGE_TITLE>
J 0
(-7990 5350);
DISPLAY 0.638298 (-7990 5350);
PAINT PINK (-7990 5350);
DISPLAY INVISIBLE (-7990 5350);
FORCEPROP 1 LAST CUSTOM_TXT_CDS <NAME_2>
J 0
(-3275 150);
FORCEPROP 1 LAST CUSTOM_TXT_CDS <NAME_1>
J 0
(-3275 275);
FORCEPROP 1 LAST CUSTOM_TXT_CDS <Q_NUMBER>
J 0
(-1503 203);
DISPLAY 1.212766 (-1503 203);
FORCEPROP 1 LAST CUSTOM_TXT_CDS <Q_PROJ>
J 0
(-2482 202);
DISPLAY 1.212766 (-2482 202);
FORCEPROP 1 LAST CUSTOM_TXT_CDS <Q_REV>
J 0
(-284 203);
DISPLAY 1.212766 (-284 203);
FORCEPROP 1 LAST CUSTOM_TXT_CDS <CON_PAGE_NUM> OF <CON_TOTAL_PAGES>
J 0
(-546 118);
DISPLAY 0.978723 (-546 118);
FORCEPROP 1 LAST Q_TITLE CPU1 VSS 2/3
J 0
(-9400 175);
DISPLAY 2.446809 (-9400 175);
PAINT GREEN (-9400 175);
FORCEPROP 2 LAST CDS_LIB pure_quanta
J 0
(-100 100);
DISPLAY INVISIBLE (-100 100);
FORCEPROP 1 LAST CDS_LMAN_SYM_OUTLINE -9475,6775,100,-125
J 0
(-100 100);
DISPLAY 0.468085 (-100 100);
PAINT GREEN (-100 100);
DISPLAY INVISIBLE (-100 100);
FORCEPROP 2 LAST PAGE_BORDER TRUE
J 0
(-7990 5350);
DISPLAY 0.638298 (-7990 5350);
PAINT PINK (-7990 5350);
DISPLAY INVISIBLE (-7990 5350);
FORCEPROP 2 LAST CDS_XR_PAGE_TITLE CR-59 : @T6G_MB_LIB.T6G(SCH_1):PAGE59
J 0
(-7990 5350);
DISPLAY 0.638298 (-7990 5350);
PAINT PINK (-7990 5350);
DISPLAY INVISIBLE (-7990 5350);
FORCEPROP 1 LAST Q_DEPT BU9
J 1
(-3863 149);
DISPLAY 1.957447 (-3863 149);
PAINT GREEN (-3863 149);
DISPLAY INVISIBLE (-3863 149);
FORCEPROP 1 LAST COMMENT_BODY TRUE
J 0
(-88 87);
DISPLAY 0.978723 (-88 87);
PAINT GREEN (-88 87);
DISPLAY INVISIBLE (-88 87);
WIRE 16 -1 (-8700 6450)(-8525 6450);
WIRE 16 -1 (-8700 6450)(-8700 6400);
WIRE 16 -1 (-8525 6400)(-8700 6400);
WIRE 16 -1 (-8700 6400)(-8700 6350);
WIRE 16 -1 (-8700 6350)(-8525 6350);
WIRE 16 -1 (-8700 6350)(-8700 6300);
WIRE 16 -1 (-8700 6300)(-8525 6300);
WIRE 16 -1 (-8700 6300)(-8700 6250);
WIRE 16 -1 (-8700 6250)(-8525 6250);
WIRE 16 -1 (-8700 6250)(-8700 6200);
WIRE 16 -1 (-8700 6200)(-8525 6200);
WIRE 16 -1 (-8700 6200)(-8700 6150);
WIRE 16 -1 (-8525 6150)(-8700 6150);
WIRE 16 -1 (-8700 6150)(-8700 6100);
WIRE 16 -1 (-8700 6100)(-8525 6100);
WIRE 16 -1 (-8700 6100)(-8700 6050);
WIRE 16 -1 (-8700 6050)(-8525 6050);
WIRE 16 -1 (-8700 6050)(-8700 6000);
WIRE 16 -1 (-8700 6000)(-8525 6000);
WIRE 16 -1 (-8700 6000)(-8700 5950);
WIRE 16 -1 (-8700 5950)(-8525 5950);
WIRE 16 -1 (-8700 5950)(-8700 5900);
WIRE 16 -1 (-8525 5900)(-8700 5900);
WIRE 16 -1 (-8700 5900)(-8700 5850);
WIRE 16 -1 (-8700 5850)(-8525 5850);
WIRE 16 -1 (-8700 5850)(-8700 5800);
WIRE 16 -1 (-8700 5800)(-8525 5800);
WIRE 16 -1 (-8700 5800)(-8700 5750);
WIRE 16 -1 (-8700 5750)(-8525 5750);
WIRE 16 -1 (-8700 5750)(-8700 5700);
WIRE 16 -1 (-8700 5700)(-8525 5700);
WIRE 16 -1 (-8700 5700)(-8700 5650);
WIRE 16 -1 (-8525 5650)(-8700 5650);
WIRE 16 -1 (-8700 5650)(-8700 5600);
WIRE 16 -1 (-8700 5600)(-8525 5600);
WIRE 16 -1 (-8700 5600)(-8700 5550);
WIRE 16 -1 (-8700 5550)(-8525 5550);
WIRE 16 -1 (-8700 5550)(-8700 5500);
WIRE 16 -1 (-8700 5500)(-8525 5500);
WIRE 16 -1 (-8700 5500)(-8700 5450);
WIRE 16 -1 (-8700 5450)(-8525 5450);
WIRE 16 -1 (-8700 5450)(-8700 5400);
WIRE 16 -1 (-8525 5400)(-8700 5400);
WIRE 16 -1 (-8700 5400)(-8700 5350);
WIRE 16 -1 (-8700 5350)(-8525 5350);
WIRE 16 -1 (-8700 5350)(-8700 5300);
WIRE 16 -1 (-8700 5300)(-8525 5300);
WIRE 16 -1 (-8700 5300)(-8700 5250);
WIRE 16 -1 (-8700 5250)(-8525 5250);
WIRE 16 -1 (-8700 5250)(-8700 5200);
WIRE 16 -1 (-8700 5200)(-8525 5200);
WIRE 16 -1 (-8700 5200)(-8700 5150);
WIRE 16 -1 (-8525 5150)(-8700 5150);
WIRE 16 -1 (-8700 5150)(-8700 5100);
WIRE 16 -1 (-8700 5100)(-8525 5100);
WIRE 16 -1 (-8700 5100)(-8700 5050);
WIRE 16 -1 (-8700 5050)(-8525 5050);
WIRE 16 -1 (-8700 5050)(-8700 5000);
WIRE 16 -1 (-8700 5000)(-8525 5000);
WIRE 16 -1 (-8700 5000)(-8700 4950);
WIRE 16 -1 (-8700 4950)(-8525 4950);
WIRE 16 -1 (-8700 4950)(-8700 4900);
WIRE 16 -1 (-8525 4900)(-8700 4900);
WIRE 16 -1 (-8700 4900)(-8700 4850);
WIRE 16 -1 (-8700 4850)(-8525 4850);
WIRE 16 -1 (-8700 4850)(-8700 4800);
WIRE 16 -1 (-8700 4800)(-8525 4800);
WIRE 16 -1 (-8700 4800)(-8700 4750);
WIRE 16 -1 (-8700 4750)(-8525 4750);
WIRE 16 -1 (-8700 4750)(-8700 4700);
WIRE 16 -1 (-8700 4700)(-8525 4700);
WIRE 16 -1 (-8700 4700)(-8700 4650);
WIRE 16 -1 (-8525 4650)(-8700 4650);
WIRE 16 -1 (-8700 4650)(-8700 4600);
WIRE 16 -1 (-8700 4600)(-8525 4600);
WIRE 16 -1 (-8700 4600)(-8700 4550);
WIRE 16 -1 (-8700 4550)(-8525 4550);
WIRE 16 -1 (-8700 4550)(-8700 4500);
WIRE 16 -1 (-8700 4500)(-8525 4500);
WIRE 16 -1 (-8700 4500)(-8700 4450);
WIRE 16 -1 (-8700 4450)(-8525 4450);
WIRE 16 -1 (-8700 4450)(-8700 4400);
WIRE 16 -1 (-8525 4400)(-8700 4400);
WIRE 16 -1 (-8700 4400)(-8700 4350);
WIRE 16 -1 (-8700 4350)(-8525 4350);
WIRE 16 -1 (-8700 4350)(-8700 4300);
WIRE 16 -1 (-8700 4300)(-8525 4300);
WIRE 16 -1 (-8700 4300)(-8700 4250);
WIRE 16 -1 (-8700 4250)(-8525 4250);
WIRE 16 -1 (-8700 4250)(-8700 4200);
WIRE 16 -1 (-8700 4200)(-8525 4200);
WIRE 16 -1 (-8700 4200)(-8700 4150);
WIRE 16 -1 (-8700 4150)(-8525 4150);
WIRE 16 -1 (-8700 4150)(-8700 4100);
WIRE 16 -1 (-8525 4100)(-8700 4100);
WIRE 16 -1 (-8700 4100)(-8700 4050);
WIRE 16 -1 (-8700 4050)(-8525 4050);
WIRE 16 -1 (-8700 4050)(-8700 4000);
WIRE 16 -1 (-8700 4000)(-8525 4000);
WIRE 16 -1 (-8700 4000)(-8700 3950);
WIRE 16 -1 (-8700 3950)(-8525 3950);
WIRE 16 -1 (-8700 3950)(-8700 3900);
WIRE 16 -1 (-8700 3900)(-8525 3900);
WIRE 16 -1 (-8700 3900)(-8700 3850);
WIRE 16 -1 (-8525 3850)(-8700 3850);
WIRE 16 -1 (-8700 3850)(-8700 3800);
WIRE 16 -1 (-8700 3800)(-8525 3800);
WIRE 16 -1 (-8700 3800)(-8700 3750);
WIRE 16 -1 (-8700 3750)(-8525 3750);
WIRE 16 -1 (-8700 3750)(-8700 3700);
WIRE 16 -1 (-8700 3700)(-8525 3700);
WIRE 16 -1 (-8700 3700)(-8700 3650);
WIRE 16 -1 (-8700 3650)(-8525 3650);
WIRE 16 -1 (-8700 3650)(-8700 3600);
WIRE 16 -1 (-8525 3600)(-8700 3600);
WIRE 16 -1 (-8700 3600)(-8700 3550);
WIRE 16 -1 (-8700 3550)(-8525 3550);
WIRE 16 -1 (-8700 3550)(-8700 3500);
WIRE 16 -1 (-8700 3500)(-8525 3500);
WIRE 16 -1 (-8700 3500)(-8700 3450);
WIRE 16 -1 (-8700 3450)(-8525 3450);
WIRE 16 -1 (-8700 3450)(-8700 3400);
WIRE 16 -1 (-8700 3400)(-8525 3400);
WIRE 16 -1 (-8700 3400)(-8700 3350);
WIRE 16 -1 (-8525 3350)(-8700 3350);
WIRE 16 -1 (-8700 3350)(-8700 3300);
WIRE 16 -1 (-8700 3300)(-8525 3300);
WIRE 16 -1 (-8700 3300)(-8700 3250);
WIRE 16 -1 (-8700 3250)(-8525 3250);
WIRE 16 -1 (-8700 3250)(-8700 3200);
WIRE 16 -1 (-8700 3200)(-8525 3200);
WIRE 16 -1 (-8700 3200)(-8700 3150);
WIRE 16 -1 (-8700 3150)(-8525 3150);
WIRE 16 -1 (-8700 3150)(-8700 3100);
WIRE 16 -1 (-8525 3100)(-8700 3100);
WIRE 16 -1 (-8700 3100)(-8700 3050);
WIRE 16 -1 (-8700 3050)(-8525 3050);
WIRE 16 -1 (-8700 3050)(-8700 3000);
WIRE 16 -1 (-8700 3000)(-8525 3000);
WIRE 16 -1 (-8700 3000)(-8700 2950);
WIRE 16 -1 (-8700 2950)(-8525 2950);
WIRE 16 -1 (-8700 2950)(-8700 2900);
WIRE 16 -1 (-8700 2900)(-8525 2900);
WIRE 16 -1 (-8700 2900)(-8700 2850);
WIRE 16 -1 (-8525 2850)(-8700 2850);
WIRE 16 -1 (-8700 2850)(-8700 2800);
WIRE 16 -1 (-8700 2800)(-8525 2800);
WIRE 16 -1 (-8700 2800)(-8700 2750);
WIRE 16 -1 (-8700 2750)(-8525 2750);
WIRE 16 -1 (-8700 2750)(-8700 2700);
WIRE 16 -1 (-8700 2700)(-8525 2700);
WIRE 16 -1 (-8700 2700)(-8700 2650);
WIRE 16 -1 (-8700 2650)(-8525 2650);
WIRE 16 -1 (-8700 2650)(-8700 2600);
WIRE 16 -1 (-8525 2600)(-8700 2600);
WIRE 16 -1 (-8700 2600)(-8700 2550);
WIRE 16 -1 (-8700 2550)(-8525 2550);
WIRE 16 -1 (-8700 2550)(-8700 2500);
WIRE 16 -1 (-8700 2500)(-8525 2500);
WIRE 16 -1 (-8700 2500)(-8700 2450);
WIRE 16 -1 (-8700 2450)(-8525 2450);
WIRE 16 -1 (-8700 2450)(-8700 2400);
WIRE 16 -1 (-8700 2400)(-8525 2400);
WIRE 16 -1 (-8700 2400)(-8700 2350);
WIRE 16 -1 (-8525 2350)(-8700 2350);
WIRE 16 -1 (-8700 2350)(-8700 2300);
WIRE 16 -1 (-8700 2300)(-8525 2300);
WIRE 16 -1 (-8700 2300)(-8700 2250);
WIRE 16 -1 (-8700 2250)(-8525 2250);
WIRE 16 -1 (-8700 2250)(-8700 2200);
WIRE 16 -1 (-8700 2200)(-8525 2200);
WIRE 16 -1 (-8700 2200)(-8700 2150);
WIRE 16 -1 (-8700 2150)(-8525 2150);
WIRE 16 -1 (-8700 2150)(-8700 2100);
WIRE 16 -1 (-8700 2100)(-8525 2100);
WIRE 16 -1 (-8700 2100)(-8700 2050);
WIRE 16 -1 (-8525 2050)(-8700 2050);
WIRE 16 -1 (-8700 2050)(-8700 2000);
WIRE 16 -1 (-8700 2000)(-8525 2000);
WIRE 16 -1 (-8700 2000)(-8700 1950);
WIRE 16 -1 (-8700 1950)(-8525 1950);
WIRE 16 -1 (-8700 1950)(-8700 1900);
WIRE 16 -1 (-8700 1900)(-8525 1900);
WIRE 16 -1 (-8700 1900)(-8700 1850);
WIRE 16 -1 (-8700 1850)(-8525 1850);
WIRE 16 -1 (-8700 1850)(-8700 1800);
WIRE 16 -1 (-8525 1800)(-8700 1800);
WIRE 16 -1 (-8700 1800)(-8700 1750);
WIRE 16 -1 (-8700 1750)(-8525 1750);
WIRE 16 -1 (-8700 1750)(-8700 1700);
WIRE 16 -1 (-8700 1700)(-8525 1700);
WIRE 16 -1 (-8700 1700)(-8700 1650);
WIRE 16 -1 (-8700 1650)(-8525 1650);
WIRE 16 -1 (-8700 1650)(-8700 1600);
WIRE 16 -1 (-8700 1600)(-8525 1600);
WIRE 16 -1 (-8700 1600)(-8700 1550);
WIRE 16 -1 (-8525 1550)(-8700 1550);
WIRE 16 -1 (-8700 1550)(-8700 1500);
WIRE 16 -1 (-8700 1500)(-8525 1500);
WIRE 16 -1 (-8700 1500)(-8700 1450);
WIRE 16 -1 (-8700 1450)(-8525 1450);
WIRE 16 -1 (-8700 1450)(-8700 1400);
WIRE 16 -1 (-8700 1400)(-8525 1400);
WIRE 16 -1 (-8700 1400)(-8700 1350);
WIRE 16 -1 (-8700 1350)(-8525 1350);
WIRE 16 -1 (-8700 1350)(-8700 1300);
WIRE 16 -1 (-8525 1300)(-8700 1300);
WIRE 16 -1 (-8700 1300)(-8700 1250);
WIRE 16 -1 (-8700 1250)(-8525 1250);
WIRE 16 -1 (-8700 1250)(-8700 1200);
WIRE 16 -1 (-8700 1200)(-8525 1200);
WIRE 16 -1 (-8700 1200)(-8700 1150);
WIRE 16 -1 (-8700 1150)(-8525 1150);
WIRE 16 -1 (-8700 1150)(-8700 1100);
WIRE 16 -1 (-8700 1100)(-8525 1100);
WIRE 16 -1 (-8700 1100)(-8700 1050);
WIRE 16 -1 (-8525 1050)(-8700 1050);
WIRE 16 -1 (-8700 1050)(-8700 1000);
WIRE 16 -1 (-8700 1000)(-8525 1000);
WIRE 16 -1 (-8700 1000)(-8700 950);
WIRE 16 -1 (-8700 950)(-8525 950);
WIRE 16 -1 (-8700 950)(-8700 900);
WIRE 16 -1 (-8700 900)(-8525 900);
WIRE 16 -1 (-8700 900)(-8700 850);
WIRE 16 -1 (-8700 850)(-8525 850);
WIRE 16 -1 (-8700 850)(-8700 800);
WIRE 16 -1 (-8525 800)(-8700 800);
WIRE 16 -1 (-8700 800)(-8700 750);
WIRE 16 -1 (-8700 750)(-8525 750);
WIRE 16 -1 (-8700 750)(-8700 700);
WIRE 16 -1 (-8700 700)(-8525 700);
WIRE 16 -1 (-8700 700)(-8700 650);
WIRE 16 -1 (-8700 650)(-8525 650);
WIRE 16 -1 (-8700 650)(-8700 600);
WIRE 16 -1 (-8700 600)(-8525 600);
WIRE 16 -1 (-8700 600)(-8700 550);
WIRE 16 -1 (-8525 550)(-8700 550);
WIRE 16 -1 (-8700 550)(-8700 500);
WIRE 16 -1 (-7425 6450)(-7250 6450);
WIRE 16 -1 (-7250 6450)(-7250 6400);
WIRE 16 -1 (-7250 6400)(-7250 6350);
WIRE 16 -1 (-7425 6400)(-7250 6400);
WIRE 16 -1 (-7250 6350)(-7250 6300);
WIRE 16 -1 (-7425 6350)(-7250 6350);
WIRE 16 -1 (-7250 6300)(-7250 6250);
WIRE 16 -1 (-7425 6300)(-7250 6300);
WIRE 16 -1 (-7250 6250)(-7250 6200);
WIRE 16 -1 (-7425 6250)(-7250 6250);
WIRE 16 -1 (-7250 6200)(-7250 6150);
WIRE 16 -1 (-7425 6200)(-7250 6200);
WIRE 16 -1 (-7425 6150)(-7250 6150);
WIRE 16 -1 (-7250 6150)(-7250 6100);
WIRE 16 -1 (-7250 6100)(-7250 6050);
WIRE 16 -1 (-7425 6100)(-7250 6100);
WIRE 16 -1 (-7250 6050)(-7250 6000);
WIRE 16 -1 (-7425 6050)(-7250 6050);
WIRE 16 -1 (-7250 6000)(-7250 5950);
WIRE 16 -1 (-7425 6000)(-7250 6000);
WIRE 16 -1 (-7250 5950)(-7250 5900);
WIRE 16 -1 (-7425 5950)(-7250 5950);
WIRE 16 -1 (-7250 5900)(-7250 5850);
WIRE 16 -1 (-7425 5900)(-7250 5900);
WIRE 16 -1 (-7250 5850)(-7250 5800);
WIRE 16 -1 (-7425 5850)(-7250 5850);
WIRE 16 -1 (-7250 5800)(-7250 5750);
WIRE 16 -1 (-7425 5800)(-7250 5800);
WIRE 16 -1 (-7250 5750)(-7250 5700);
WIRE 16 -1 (-7425 5750)(-7250 5750);
WIRE 16 -1 (-7250 5700)(-7250 5650);
WIRE 16 -1 (-7425 5700)(-7250 5700);
WIRE 16 -1 (-7425 5650)(-7250 5650);
WIRE 16 -1 (-7250 5650)(-7250 5600);
WIRE 16 -1 (-7250 5600)(-7250 5550);
WIRE 16 -1 (-7425 5600)(-7250 5600);
WIRE 16 -1 (-7250 5550)(-7250 5500);
WIRE 16 -1 (-7425 5550)(-7250 5550);
WIRE 16 -1 (-7250 5500)(-7250 5450);
WIRE 16 -1 (-7425 5500)(-7250 5500);
WIRE 16 -1 (-7250 5450)(-7250 5400);
WIRE 16 -1 (-7425 5450)(-7250 5450);
WIRE 16 -1 (-7250 5400)(-7250 5350);
WIRE 16 -1 (-7425 5400)(-7250 5400);
WIRE 16 -1 (-7250 5350)(-7250 5300);
WIRE 16 -1 (-7425 5350)(-7250 5350);
WIRE 16 -1 (-7250 5300)(-7250 5250);
WIRE 16 -1 (-7425 5300)(-7250 5300);
WIRE 16 -1 (-7250 5250)(-7250 5200);
WIRE 16 -1 (-7425 5250)(-7250 5250);
WIRE 16 -1 (-7250 5200)(-7250 5150);
WIRE 16 -1 (-7425 5200)(-7250 5200);
WIRE 16 -1 (-7425 5150)(-7250 5150);
WIRE 16 -1 (-7250 5150)(-7250 5100);
WIRE 16 -1 (-7250 5100)(-7250 5050);
WIRE 16 -1 (-7425 5100)(-7250 5100);
WIRE 16 -1 (-7250 5050)(-7250 5000);
WIRE 16 -1 (-7425 5050)(-7250 5050);
WIRE 16 -1 (-7250 5000)(-7250 4950);
WIRE 16 -1 (-7425 5000)(-7250 5000);
WIRE 16 -1 (-7250 4950)(-7250 4900);
WIRE 16 -1 (-7425 4950)(-7250 4950);
WIRE 16 -1 (-7250 4900)(-7250 4850);
WIRE 16 -1 (-7425 4900)(-7250 4900);
WIRE 16 -1 (-7250 4850)(-7250 4800);
WIRE 16 -1 (-7425 4850)(-7250 4850);
WIRE 16 -1 (-7250 4800)(-7250 4750);
WIRE 16 -1 (-7425 4800)(-7250 4800);
WIRE 16 -1 (-7250 4750)(-7250 4700);
WIRE 16 -1 (-7425 4750)(-7250 4750);
WIRE 16 -1 (-7250 4700)(-7250 4650);
WIRE 16 -1 (-7425 4700)(-7250 4700);
WIRE 16 -1 (-7425 4650)(-7250 4650);
WIRE 16 -1 (-7250 4650)(-7250 4600);
WIRE 16 -1 (-7250 4600)(-7250 4550);
WIRE 16 -1 (-7425 4600)(-7250 4600);
WIRE 16 -1 (-7250 4550)(-7250 4500);
WIRE 16 -1 (-7425 4550)(-7250 4550);
WIRE 16 -1 (-7250 4500)(-7250 4450);
WIRE 16 -1 (-7425 4500)(-7250 4500);
WIRE 16 -1 (-7250 4450)(-7250 4400);
WIRE 16 -1 (-7425 4450)(-7250 4450);
WIRE 16 -1 (-7250 4400)(-7250 4350);
WIRE 16 -1 (-7425 4400)(-7250 4400);
WIRE 16 -1 (-7250 4350)(-7250 4300);
WIRE 16 -1 (-7425 4350)(-7250 4350);
WIRE 16 -1 (-7250 4300)(-7250 4250);
WIRE 16 -1 (-7425 4300)(-7250 4300);
WIRE 16 -1 (-7250 4250)(-7250 4200);
WIRE 16 -1 (-7425 4250)(-7250 4250);
WIRE 16 -1 (-7250 4200)(-7250 4150);
WIRE 16 -1 (-7425 4200)(-7250 4200);
WIRE 16 -1 (-7250 4150)(-7250 4100);
WIRE 16 -1 (-7425 4150)(-7250 4150);
WIRE 16 -1 (-7425 4100)(-7250 4100);
WIRE 16 -1 (-7250 4100)(-7250 4050);
WIRE 16 -1 (-7250 4050)(-7250 4000);
WIRE 16 -1 (-7425 4050)(-7250 4050);
WIRE 16 -1 (-7250 4000)(-7250 3950);
WIRE 16 -1 (-7425 4000)(-7250 4000);
WIRE 16 -1 (-7250 3950)(-7250 3900);
WIRE 16 -1 (-7425 3950)(-7250 3950);
WIRE 16 -1 (-7250 3900)(-7250 3850);
WIRE 16 -1 (-7425 3900)(-7250 3900);
WIRE 16 -1 (-7250 3850)(-7250 3800);
WIRE 16 -1 (-7425 3850)(-7250 3850);
WIRE 16 -1 (-7250 3800)(-7250 3750);
WIRE 16 -1 (-7425 3800)(-7250 3800);
WIRE 16 -1 (-7250 3750)(-7250 3700);
WIRE 16 -1 (-7425 3750)(-7250 3750);
WIRE 16 -1 (-7250 3700)(-7250 3650);
WIRE 16 -1 (-7425 3700)(-7250 3700);
WIRE 16 -1 (-7250 3650)(-7250 3600);
WIRE 16 -1 (-7425 3650)(-7250 3650);
WIRE 16 -1 (-7425 3600)(-7250 3600);
WIRE 16 -1 (-7250 3600)(-7250 3550);
WIRE 16 -1 (-7250 3550)(-7250 3500);
WIRE 16 -1 (-7425 3550)(-7250 3550);
WIRE 16 -1 (-7250 3500)(-7250 3450);
WIRE 16 -1 (-7425 3500)(-7250 3500);
WIRE 16 -1 (-7250 3450)(-7250 3400);
WIRE 16 -1 (-7425 3450)(-7250 3450);
WIRE 16 -1 (-7250 3400)(-7250 3350);
WIRE 16 -1 (-7425 3400)(-7250 3400);
WIRE 16 -1 (-7250 3350)(-7250 3300);
WIRE 16 -1 (-7425 3350)(-7250 3350);
WIRE 16 -1 (-7250 3300)(-7250 3250);
WIRE 16 -1 (-7425 3300)(-7250 3300);
WIRE 16 -1 (-7250 3250)(-7250 3200);
WIRE 16 -1 (-7425 3250)(-7250 3250);
WIRE 16 -1 (-7250 3200)(-7250 3150);
WIRE 16 -1 (-7425 3200)(-7250 3200);
WIRE 16 -1 (-7250 3150)(-7250 3100);
WIRE 16 -1 (-7425 3150)(-7250 3150);
WIRE 16 -1 (-7425 3100)(-7250 3100);
WIRE 16 -1 (-7250 3100)(-7250 3050);
WIRE 16 -1 (-7250 3050)(-7250 3000);
WIRE 16 -1 (-7425 3050)(-7250 3050);
WIRE 16 -1 (-7250 3000)(-7250 2950);
WIRE 16 -1 (-7425 3000)(-7250 3000);
WIRE 16 -1 (-7250 2950)(-7250 2900);
WIRE 16 -1 (-7425 2950)(-7250 2950);
WIRE 16 -1 (-7250 2900)(-7250 2850);
WIRE 16 -1 (-7425 2900)(-7250 2900);
WIRE 16 -1 (-7250 2850)(-7250 2800);
WIRE 16 -1 (-7425 2850)(-7250 2850);
WIRE 16 -1 (-7250 2800)(-7250 2750);
WIRE 16 -1 (-7425 2800)(-7250 2800);
WIRE 16 -1 (-7250 2750)(-7250 2700);
WIRE 16 -1 (-7425 2750)(-7250 2750);
WIRE 16 -1 (-7250 2700)(-7250 2650);
WIRE 16 -1 (-7425 2700)(-7250 2700);
WIRE 16 -1 (-7250 2650)(-7250 2600);
WIRE 16 -1 (-7425 2650)(-7250 2650);
WIRE 16 -1 (-7425 2600)(-7250 2600);
WIRE 16 -1 (-7250 2600)(-7250 2550);
WIRE 16 -1 (-7250 2550)(-7250 2500);
WIRE 16 -1 (-7425 2550)(-7250 2550);
WIRE 16 -1 (-7250 2500)(-7250 2450);
WIRE 16 -1 (-7425 2500)(-7250 2500);
WIRE 16 -1 (-7250 2450)(-7250 2400);
WIRE 16 -1 (-7425 2450)(-7250 2450);
WIRE 16 -1 (-7250 2400)(-7250 2350);
WIRE 16 -1 (-7425 2400)(-7250 2400);
WIRE 16 -1 (-7250 2350)(-7250 2300);
WIRE 16 -1 (-7425 2350)(-7250 2350);
WIRE 16 -1 (-7250 2300)(-7250 2250);
WIRE 16 -1 (-7425 2300)(-7250 2300);
WIRE 16 -1 (-7250 2250)(-7250 2200);
WIRE 16 -1 (-7425 2250)(-7250 2250);
WIRE 16 -1 (-7250 2200)(-7250 2150);
WIRE 16 -1 (-7425 2200)(-7250 2200);
WIRE 16 -1 (-7250 2150)(-7250 2100);
WIRE 16 -1 (-7425 2150)(-7250 2150);
WIRE 16 -1 (-7250 2100)(-7250 2050);
WIRE 16 -1 (-7425 2100)(-7250 2100);
WIRE 16 -1 (-7425 2050)(-7250 2050);
WIRE 16 -1 (-7250 2050)(-7250 2000);
WIRE 16 -1 (-7250 2000)(-7250 1950);
WIRE 16 -1 (-7425 2000)(-7250 2000);
WIRE 16 -1 (-7250 1950)(-7250 1900);
WIRE 16 -1 (-7425 1950)(-7250 1950);
WIRE 16 -1 (-7250 1900)(-7250 1850);
WIRE 16 -1 (-7425 1900)(-7250 1900);
WIRE 16 -1 (-7250 1850)(-7250 1800);
WIRE 16 -1 (-7425 1850)(-7250 1850);
WIRE 16 -1 (-7250 1800)(-7250 1750);
WIRE 16 -1 (-7425 1800)(-7250 1800);
WIRE 16 -1 (-7250 1750)(-7250 1700);
WIRE 16 -1 (-7425 1750)(-7250 1750);
WIRE 16 -1 (-7250 1700)(-7250 1650);
WIRE 16 -1 (-7425 1700)(-7250 1700);
WIRE 16 -1 (-7250 1650)(-7250 1600);
WIRE 16 -1 (-7425 1650)(-7250 1650);
WIRE 16 -1 (-7250 1600)(-7250 1550);
WIRE 16 -1 (-7425 1600)(-7250 1600);
WIRE 16 -1 (-7425 1550)(-7250 1550);
WIRE 16 -1 (-7250 1550)(-7250 1500);
WIRE 16 -1 (-7250 1500)(-7250 1450);
WIRE 16 -1 (-7425 1500)(-7250 1500);
WIRE 16 -1 (-7250 1450)(-7250 1400);
WIRE 16 -1 (-7425 1450)(-7250 1450);
WIRE 16 -1 (-7250 1400)(-7250 1350);
WIRE 16 -1 (-7425 1400)(-7250 1400);
WIRE 16 -1 (-7250 1350)(-7250 1300);
WIRE 16 -1 (-7425 1350)(-7250 1350);
WIRE 16 -1 (-7250 1300)(-7250 1250);
WIRE 16 -1 (-7425 1300)(-7250 1300);
WIRE 16 -1 (-7250 1250)(-7250 1200);
WIRE 16 -1 (-7425 1250)(-7250 1250);
WIRE 16 -1 (-7250 1200)(-7250 1150);
WIRE 16 -1 (-7425 1200)(-7250 1200);
WIRE 16 -1 (-7250 1150)(-7250 1100);
WIRE 16 -1 (-7425 1150)(-7250 1150);
WIRE 16 -1 (-7250 1100)(-7250 1050);
WIRE 16 -1 (-7425 1100)(-7250 1100);
WIRE 16 -1 (-7425 1050)(-7250 1050);
WIRE 16 -1 (-7250 1050)(-7250 1000);
WIRE 16 -1 (-7250 1000)(-7250 950);
WIRE 16 -1 (-7425 1000)(-7250 1000);
WIRE 16 -1 (-7250 950)(-7250 900);
WIRE 16 -1 (-7425 950)(-7250 950);
WIRE 16 -1 (-7250 900)(-7250 850);
WIRE 16 -1 (-7425 900)(-7250 900);
WIRE 16 -1 (-7250 850)(-7250 800);
WIRE 16 -1 (-7425 850)(-7250 850);
WIRE 16 -1 (-7250 800)(-7250 750);
WIRE 16 -1 (-7425 800)(-7250 800);
WIRE 16 -1 (-7250 750)(-7250 700);
WIRE 16 -1 (-7425 750)(-7250 750);
WIRE 16 -1 (-7250 700)(-7250 650);
WIRE 16 -1 (-7425 700)(-7250 700);
WIRE 16 -1 (-7250 650)(-7250 600);
WIRE 16 -1 (-7425 650)(-7250 650);
WIRE 16 -1 (-7250 525)(-7250 600);
WIRE 16 -1 (-7425 600)(-7250 600);
WIRE 16 -1 (-6675 6400)(-6500 6400);
WIRE 16 -1 (-6675 6400)(-6675 6350);
WIRE 16 -1 (-6500 6350)(-6675 6350);
WIRE 16 -1 (-6675 6350)(-6675 6300);
WIRE 16 -1 (-6675 6300)(-6500 6300);
WIRE 16 -1 (-6675 6300)(-6675 6250);
WIRE 16 -1 (-6675 6250)(-6500 6250);
WIRE 16 -1 (-6675 6250)(-6675 6200);
WIRE 16 -1 (-6675 6200)(-6500 6200);
WIRE 16 -1 (-6675 6200)(-6675 6150);
WIRE 16 -1 (-6675 6150)(-6500 6150);
WIRE 16 -1 (-6675 6150)(-6675 6100);
WIRE 16 -1 (-6500 6100)(-6675 6100);
WIRE 16 -1 (-6675 6100)(-6675 6050);
WIRE 16 -1 (-6675 6050)(-6500 6050);
WIRE 16 -1 (-6675 6050)(-6675 6000);
WIRE 16 -1 (-6675 6000)(-6500 6000);
WIRE 16 -1 (-6675 6000)(-6675 5950);
WIRE 16 -1 (-6675 5950)(-6500 5950);
WIRE 16 -1 (-6675 5950)(-6675 5900);
WIRE 16 -1 (-6675 5900)(-6500 5900);
WIRE 16 -1 (-6675 5900)(-6675 5850);
WIRE 16 -1 (-6500 5850)(-6675 5850);
WIRE 16 -1 (-6675 5850)(-6675 5800);
WIRE 16 -1 (-6675 5800)(-6500 5800);
WIRE 16 -1 (-6675 5800)(-6675 5750);
WIRE 16 -1 (-6675 5750)(-6500 5750);
WIRE 16 -1 (-6675 5750)(-6675 5700);
WIRE 16 -1 (-6675 5700)(-6500 5700);
WIRE 16 -1 (-6675 5700)(-6675 5650);
WIRE 16 -1 (-6675 5650)(-6500 5650);
WIRE 16 -1 (-6675 5650)(-6675 5600);
WIRE 16 -1 (-6500 5600)(-6675 5600);
WIRE 16 -1 (-6675 5600)(-6675 5550);
WIRE 16 -1 (-6675 5550)(-6500 5550);
WIRE 16 -1 (-6675 5550)(-6675 5500);
WIRE 16 -1 (-6675 5500)(-6500 5500);
WIRE 16 -1 (-6675 5500)(-6675 5450);
WIRE 16 -1 (-6675 5450)(-6500 5450);
WIRE 16 -1 (-6675 5450)(-6675 5400);
WIRE 16 -1 (-6675 5400)(-6500 5400);
WIRE 16 -1 (-6675 5400)(-6675 5350);
WIRE 16 -1 (-6500 5350)(-6675 5350);
WIRE 16 -1 (-6675 5350)(-6675 5300);
WIRE 16 -1 (-6675 5300)(-6500 5300);
WIRE 16 -1 (-6675 5300)(-6675 5250);
WIRE 16 -1 (-6675 5250)(-6500 5250);
WIRE 16 -1 (-6675 5250)(-6675 5200);
WIRE 16 -1 (-6675 5200)(-6500 5200);
WIRE 16 -1 (-6675 5200)(-6675 5150);
WIRE 16 -1 (-6675 5150)(-6500 5150);
WIRE 16 -1 (-6675 5150)(-6675 5100);
WIRE 16 -1 (-6500 5100)(-6675 5100);
WIRE 16 -1 (-6675 5100)(-6675 5050);
WIRE 16 -1 (-6675 5050)(-6500 5050);
WIRE 16 -1 (-6675 5050)(-6675 5000);
WIRE 16 -1 (-6675 5000)(-6500 5000);
WIRE 16 -1 (-6675 5000)(-6675 4950);
WIRE 16 -1 (-6675 4950)(-6500 4950);
WIRE 16 -1 (-6675 4950)(-6675 4900);
WIRE 16 -1 (-6675 4900)(-6500 4900);
WIRE 16 -1 (-6675 4900)(-6675 4850);
WIRE 16 -1 (-6500 4850)(-6675 4850);
WIRE 16 -1 (-6675 4850)(-6675 4800);
WIRE 16 -1 (-6675 4800)(-6500 4800);
WIRE 16 -1 (-6675 4800)(-6675 4750);
WIRE 16 -1 (-6675 4750)(-6500 4750);
WIRE 16 -1 (-6675 4750)(-6675 4700);
WIRE 16 -1 (-6675 4700)(-6500 4700);
WIRE 16 -1 (-6675 4700)(-6675 4650);
WIRE 16 -1 (-6675 4650)(-6500 4650);
WIRE 16 -1 (-6675 4650)(-6675 4600);
WIRE 16 -1 (-6500 4600)(-6675 4600);
WIRE 16 -1 (-6675 4600)(-6675 4550);
WIRE 16 -1 (-6675 4550)(-6500 4550);
WIRE 16 -1 (-6675 4550)(-6675 4500);
WIRE 16 -1 (-6675 4500)(-6500 4500);
WIRE 16 -1 (-6675 4500)(-6675 4450);
WIRE 16 -1 (-6675 4450)(-6500 4450);
WIRE 16 -1 (-6675 4450)(-6675 4400);
WIRE 16 -1 (-6675 4400)(-6500 4400);
WIRE 16 -1 (-6675 4400)(-6675 4350);
WIRE 16 -1 (-6500 4350)(-6675 4350);
WIRE 16 -1 (-6675 4350)(-6675 4300);
WIRE 16 -1 (-6675 4300)(-6500 4300);
WIRE 16 -1 (-6675 4300)(-6675 4250);
WIRE 16 -1 (-6675 4250)(-6500 4250);
WIRE 16 -1 (-6675 4250)(-6675 4200);
WIRE 16 -1 (-6675 4200)(-6500 4200);
WIRE 16 -1 (-6675 4200)(-6675 4150);
WIRE 16 -1 (-6675 4150)(-6500 4150);
WIRE 16 -1 (-6675 4150)(-6675 4100);
WIRE 16 -1 (-6675 4100)(-6500 4100);
WIRE 16 -1 (-6675 4100)(-6675 4050);
WIRE 16 -1 (-6500 4050)(-6675 4050);
WIRE 16 -1 (-6675 4050)(-6675 4000);
WIRE 16 -1 (-6675 4000)(-6500 4000);
WIRE 16 -1 (-6675 4000)(-6675 3950);
WIRE 16 -1 (-6675 3950)(-6500 3950);
WIRE 16 -1 (-6675 3950)(-6675 3900);
WIRE 16 -1 (-6675 3900)(-6500 3900);
WIRE 16 -1 (-6675 3900)(-6675 3850);
WIRE 16 -1 (-6675 3850)(-6500 3850);
WIRE 16 -1 (-6675 3850)(-6675 3800);
WIRE 16 -1 (-6500 3800)(-6675 3800);
WIRE 16 -1 (-6675 3800)(-6675 3750);
WIRE 16 -1 (-6675 3750)(-6500 3750);
WIRE 16 -1 (-6675 3750)(-6675 3700);
WIRE 16 -1 (-6675 3700)(-6500 3700);
WIRE 16 -1 (-6675 3700)(-6675 3650);
WIRE 16 -1 (-6675 3650)(-6500 3650);
WIRE 16 -1 (-6675 3650)(-6675 3600);
WIRE 16 -1 (-6675 3600)(-6500 3600);
WIRE 16 -1 (-6675 3600)(-6675 3550);
WIRE 16 -1 (-6500 3550)(-6675 3550);
WIRE 16 -1 (-6675 3550)(-6675 3500);
WIRE 16 -1 (-6675 3500)(-6500 3500);
WIRE 16 -1 (-6675 3500)(-6675 3450);
WIRE 16 -1 (-6675 3450)(-6500 3450);
WIRE 16 -1 (-6675 3450)(-6675 3400);
WIRE 16 -1 (-6675 3400)(-6500 3400);
WIRE 16 -1 (-6675 3400)(-6675 3350);
WIRE 16 -1 (-6675 3350)(-6500 3350);
WIRE 16 -1 (-6675 3350)(-6675 3300);
WIRE 16 -1 (-6500 3300)(-6675 3300);
WIRE 16 -1 (-6675 3300)(-6675 3250);
WIRE 16 -1 (-6675 3250)(-6500 3250);
WIRE 16 -1 (-6675 3250)(-6675 3200);
WIRE 16 -1 (-6675 3200)(-6500 3200);
WIRE 16 -1 (-6675 3200)(-6675 3150);
WIRE 16 -1 (-6675 3150)(-6500 3150);
WIRE 16 -1 (-6675 3150)(-6675 3100);
WIRE 16 -1 (-6675 3100)(-6500 3100);
WIRE 16 -1 (-6675 3100)(-6675 3050);
WIRE 16 -1 (-6500 3050)(-6675 3050);
WIRE 16 -1 (-6675 3050)(-6675 3000);
WIRE 16 -1 (-6675 3000)(-6500 3000);
WIRE 16 -1 (-6675 3000)(-6675 2950);
WIRE 16 -1 (-6675 2950)(-6500 2950);
WIRE 16 -1 (-6675 2950)(-6675 2900);
WIRE 16 -1 (-6675 2900)(-6500 2900);
WIRE 16 -1 (-6675 2900)(-6675 2850);
WIRE 16 -1 (-6675 2850)(-6500 2850);
WIRE 16 -1 (-6675 2850)(-6675 2800);
WIRE 16 -1 (-6500 2800)(-6675 2800);
WIRE 16 -1 (-6675 2800)(-6675 2750);
WIRE 16 -1 (-6675 2750)(-6500 2750);
WIRE 16 -1 (-6675 2750)(-6675 2700);
WIRE 16 -1 (-6675 2700)(-6500 2700);
WIRE 16 -1 (-6675 2700)(-6675 2650);
WIRE 16 -1 (-6675 2650)(-6500 2650);
WIRE 16 -1 (-6675 2650)(-6675 2600);
WIRE 16 -1 (-6675 2600)(-6500 2600);
WIRE 16 -1 (-6675 2600)(-6675 2550);
WIRE 16 -1 (-6500 2550)(-6675 2550);
WIRE 16 -1 (-6675 2550)(-6675 2500);
WIRE 16 -1 (-6675 2500)(-6500 2500);
WIRE 16 -1 (-6675 2500)(-6675 2450);
WIRE 16 -1 (-6675 2450)(-6500 2450);
WIRE 16 -1 (-6675 2450)(-6675 2400);
WIRE 16 -1 (-6675 2400)(-6500 2400);
WIRE 16 -1 (-6675 2400)(-6675 2350);
WIRE 16 -1 (-6675 2350)(-6500 2350);
WIRE 16 -1 (-6675 2350)(-6675 2300);
WIRE 16 -1 (-6500 2300)(-6675 2300);
WIRE 16 -1 (-6675 2300)(-6675 2250);
WIRE 16 -1 (-6675 2250)(-6500 2250);
WIRE 16 -1 (-6675 2250)(-6675 2200);
WIRE 16 -1 (-6675 2200)(-6500 2200);
WIRE 16 -1 (-6675 2200)(-6675 2150);
WIRE 16 -1 (-6675 2150)(-6500 2150);
WIRE 16 -1 (-6675 2150)(-6675 2100);
WIRE 16 -1 (-6675 2100)(-6500 2100);
WIRE 16 -1 (-6675 2100)(-6675 2050);
WIRE 16 -1 (-6675 2050)(-6500 2050);
WIRE 16 -1 (-6675 2050)(-6675 2000);
WIRE 16 -1 (-6500 2000)(-6675 2000);
WIRE 16 -1 (-6675 2000)(-6675 1950);
WIRE 16 -1 (-6675 1950)(-6500 1950);
WIRE 16 -1 (-6675 1950)(-6675 1900);
WIRE 16 -1 (-6675 1900)(-6500 1900);
WIRE 16 -1 (-6675 1900)(-6675 1850);
WIRE 16 -1 (-6675 1850)(-6500 1850);
WIRE 16 -1 (-6675 1850)(-6675 1800);
WIRE 16 -1 (-6675 1800)(-6500 1800);
WIRE 16 -1 (-6675 1800)(-6675 1750);
WIRE 16 -1 (-6500 1750)(-6675 1750);
WIRE 16 -1 (-6675 1750)(-6675 1700);
WIRE 16 -1 (-6675 1700)(-6500 1700);
WIRE 16 -1 (-6675 1700)(-6675 1650);
WIRE 16 -1 (-6675 1650)(-6500 1650);
WIRE 16 -1 (-6675 1650)(-6675 1600);
WIRE 16 -1 (-6675 1600)(-6500 1600);
WIRE 16 -1 (-6675 1600)(-6675 1550);
WIRE 16 -1 (-6675 1550)(-6500 1550);
WIRE 16 -1 (-6675 1550)(-6675 1500);
WIRE 16 -1 (-6500 1500)(-6675 1500);
WIRE 16 -1 (-6675 1500)(-6675 1450);
WIRE 16 -1 (-6675 1450)(-6500 1450);
WIRE 16 -1 (-6675 1450)(-6675 1400);
WIRE 16 -1 (-6675 1400)(-6500 1400);
WIRE 16 -1 (-6675 1400)(-6675 1350);
WIRE 16 -1 (-6675 1350)(-6500 1350);
WIRE 16 -1 (-6675 1350)(-6675 1300);
WIRE 16 -1 (-6675 1300)(-6500 1300);
WIRE 16 -1 (-6675 1300)(-6675 1250);
WIRE 16 -1 (-6500 1250)(-6675 1250);
WIRE 16 -1 (-6675 1250)(-6675 1200);
WIRE 16 -1 (-6675 1200)(-6500 1200);
WIRE 16 -1 (-6675 1200)(-6675 1150);
WIRE 16 -1 (-6675 1150)(-6500 1150);
WIRE 16 -1 (-6675 1150)(-6675 1100);
WIRE 16 -1 (-6675 1100)(-6500 1100);
WIRE 16 -1 (-6675 1100)(-6675 1050);
WIRE 16 -1 (-6675 1050)(-6500 1050);
WIRE 16 -1 (-6675 1050)(-6675 1000);
WIRE 16 -1 (-6500 1000)(-6675 1000);
WIRE 16 -1 (-6675 1000)(-6675 950);
WIRE 16 -1 (-6675 950)(-6500 950);
WIRE 16 -1 (-6675 950)(-6675 900);
WIRE 16 -1 (-6675 900)(-6500 900);
WIRE 16 -1 (-6675 900)(-6675 850);
WIRE 16 -1 (-6675 850)(-6500 850);
WIRE 16 -1 (-6675 850)(-6675 800);
WIRE 16 -1 (-6675 800)(-6500 800);
WIRE 16 -1 (-6675 800)(-6675 750);
WIRE 16 -1 (-6500 750)(-6675 750);
WIRE 16 -1 (-6675 750)(-6675 700);
WIRE 16 -1 (-6675 700)(-6500 700);
WIRE 16 -1 (-6675 700)(-6675 650);
WIRE 16 -1 (-6675 650)(-6500 650);
WIRE 16 -1 (-6675 650)(-6675 600);
WIRE 16 -1 (-6675 600)(-6500 600);
WIRE 16 -1 (-6675 600)(-6675 550);
WIRE 16 -1 (-6675 550)(-6500 550);
WIRE 16 -1 (-6675 525)(-6675 550);
WIRE 16 -1 (-5400 6350)(-5225 6350);
WIRE 16 -1 (-5225 6350)(-5225 6300);
WIRE 16 -1 (-5225 6300)(-5225 6250);
WIRE 16 -1 (-5400 6300)(-5225 6300);
WIRE 16 -1 (-5225 6250)(-5225 6200);
WIRE 16 -1 (-5400 6250)(-5225 6250);
WIRE 16 -1 (-5225 6200)(-5225 6150);
WIRE 16 -1 (-5400 6200)(-5225 6200);
WIRE 16 -1 (-5400 6150)(-5225 6150);
WIRE 16 -1 (-5225 6150)(-5225 6100);
WIRE 16 -1 (-5225 6100)(-5225 6050);
WIRE 16 -1 (-5400 6100)(-5225 6100);
WIRE 16 -1 (-5225 6050)(-5225 6000);
WIRE 16 -1 (-5400 6050)(-5225 6050);
WIRE 16 -1 (-5225 6000)(-5225 5950);
WIRE 16 -1 (-5400 6000)(-5225 6000);
WIRE 16 -1 (-5225 5950)(-5225 5900);
WIRE 16 -1 (-5400 5950)(-5225 5950);
WIRE 16 -1 (-5225 5900)(-5225 5850);
WIRE 16 -1 (-5400 5900)(-5225 5900);
WIRE 16 -1 (-5225 5850)(-5225 5800);
WIRE 16 -1 (-5400 5850)(-5225 5850);
WIRE 16 -1 (-5225 5800)(-5225 5750);
WIRE 16 -1 (-5400 5800)(-5225 5800);
WIRE 16 -1 (-5225 5750)(-5225 5700);
WIRE 16 -1 (-5400 5750)(-5225 5750);
WIRE 16 -1 (-5225 5700)(-5225 5650);
WIRE 16 -1 (-5400 5700)(-5225 5700);
WIRE 16 -1 (-5400 5650)(-5225 5650);
WIRE 16 -1 (-5225 5650)(-5225 5600);
WIRE 16 -1 (-5225 5600)(-5225 5550);
WIRE 16 -1 (-5400 5600)(-5225 5600);
WIRE 16 -1 (-5225 5550)(-5225 5500);
WIRE 16 -1 (-5400 5550)(-5225 5550);
WIRE 16 -1 (-5225 5500)(-5225 5450);
WIRE 16 -1 (-5400 5500)(-5225 5500);
WIRE 16 -1 (-5225 5450)(-5225 5400);
WIRE 16 -1 (-5400 5450)(-5225 5450);
WIRE 16 -1 (-5225 5400)(-5225 5350);
WIRE 16 -1 (-5400 5400)(-5225 5400);
WIRE 16 -1 (-5225 5350)(-5225 5300);
WIRE 16 -1 (-5400 5350)(-5225 5350);
WIRE 16 -1 (-5225 5300)(-5225 5250);
WIRE 16 -1 (-5400 5300)(-5225 5300);
WIRE 16 -1 (-5225 5250)(-5225 5200);
WIRE 16 -1 (-5400 5250)(-5225 5250);
WIRE 16 -1 (-5225 5200)(-5225 5150);
WIRE 16 -1 (-5400 5200)(-5225 5200);
WIRE 16 -1 (-5400 5150)(-5225 5150);
WIRE 16 -1 (-5225 5150)(-5225 5100);
WIRE 16 -1 (-5225 5100)(-5225 5050);
WIRE 16 -1 (-5400 5100)(-5225 5100);
WIRE 16 -1 (-5225 5050)(-5225 5000);
WIRE 16 -1 (-5400 5050)(-5225 5050);
WIRE 16 -1 (-5225 5000)(-5225 4950);
WIRE 16 -1 (-5400 5000)(-5225 5000);
WIRE 16 -1 (-5225 4950)(-5225 4900);
WIRE 16 -1 (-5400 4950)(-5225 4950);
WIRE 16 -1 (-5225 4900)(-5225 4850);
WIRE 16 -1 (-5400 4900)(-5225 4900);
WIRE 16 -1 (-5225 4850)(-5225 4800);
WIRE 16 -1 (-5400 4850)(-5225 4850);
WIRE 16 -1 (-5225 4800)(-5225 4750);
WIRE 16 -1 (-5400 4800)(-5225 4800);
WIRE 16 -1 (-5225 4750)(-5225 4700);
WIRE 16 -1 (-5400 4750)(-5225 4750);
WIRE 16 -1 (-5225 4700)(-5225 4650);
WIRE 16 -1 (-5400 4700)(-5225 4700);
WIRE 16 -1 (-5400 4650)(-5225 4650);
WIRE 16 -1 (-5225 4650)(-5225 4600);
WIRE 16 -1 (-5225 4600)(-5225 4550);
WIRE 16 -1 (-5400 4600)(-5225 4600);
WIRE 16 -1 (-5225 4550)(-5225 4500);
WIRE 16 -1 (-5400 4550)(-5225 4550);
WIRE 16 -1 (-5225 4500)(-5225 4450);
WIRE 16 -1 (-5400 4500)(-5225 4500);
WIRE 16 -1 (-5225 4450)(-5225 4400);
WIRE 16 -1 (-5400 4450)(-5225 4450);
WIRE 16 -1 (-5225 4400)(-5225 4350);
WIRE 16 -1 (-5400 4400)(-5225 4400);
WIRE 16 -1 (-5225 4350)(-5225 4300);
WIRE 16 -1 (-5400 4350)(-5225 4350);
WIRE 16 -1 (-5225 4300)(-5225 4250);
WIRE 16 -1 (-5400 4300)(-5225 4300);
WIRE 16 -1 (-5225 4250)(-5225 4200);
WIRE 16 -1 (-5400 4250)(-5225 4250);
WIRE 16 -1 (-5225 4200)(-5225 4150);
WIRE 16 -1 (-5400 4200)(-5225 4200);
WIRE 16 -1 (-5225 4150)(-5225 4100);
WIRE 16 -1 (-5400 4150)(-5225 4150);
WIRE 16 -1 (-5400 4100)(-5225 4100);
WIRE 16 -1 (-5225 4100)(-5225 4050);
WIRE 16 -1 (-5225 4050)(-5225 4000);
WIRE 16 -1 (-5400 4050)(-5225 4050);
WIRE 16 -1 (-5225 4000)(-5225 3950);
WIRE 16 -1 (-5400 4000)(-5225 4000);
WIRE 16 -1 (-5225 3950)(-5225 3900);
WIRE 16 -1 (-5400 3950)(-5225 3950);
WIRE 16 -1 (-5225 3900)(-5225 3850);
WIRE 16 -1 (-5400 3900)(-5225 3900);
WIRE 16 -1 (-5225 3850)(-5225 3800);
WIRE 16 -1 (-5400 3850)(-5225 3850);
WIRE 16 -1 (-5225 3800)(-5225 3750);
WIRE 16 -1 (-5400 3800)(-5225 3800);
WIRE 16 -1 (-5225 3750)(-5225 3700);
WIRE 16 -1 (-5400 3750)(-5225 3750);
WIRE 16 -1 (-5225 3700)(-5225 3650);
WIRE 16 -1 (-5400 3700)(-5225 3700);
WIRE 16 -1 (-5225 3650)(-5225 3600);
WIRE 16 -1 (-5400 3650)(-5225 3650);
WIRE 16 -1 (-5400 3600)(-5225 3600);
WIRE 16 -1 (-5225 3600)(-5225 3550);
WIRE 16 -1 (-5225 3550)(-5225 3500);
WIRE 16 -1 (-5400 3550)(-5225 3550);
WIRE 16 -1 (-5225 3500)(-5225 3450);
WIRE 16 -1 (-5400 3500)(-5225 3500);
WIRE 16 -1 (-5225 3450)(-5225 3400);
WIRE 16 -1 (-5400 3450)(-5225 3450);
WIRE 16 -1 (-5225 3400)(-5225 3350);
WIRE 16 -1 (-5400 3400)(-5225 3400);
WIRE 16 -1 (-5225 3350)(-5225 3300);
WIRE 16 -1 (-5400 3350)(-5225 3350);
WIRE 16 -1 (-5225 3300)(-5225 3250);
WIRE 16 -1 (-5400 3300)(-5225 3300);
WIRE 16 -1 (-5225 3250)(-5225 3200);
WIRE 16 -1 (-5400 3250)(-5225 3250);
WIRE 16 -1 (-5225 3200)(-5225 3150);
WIRE 16 -1 (-5400 3200)(-5225 3200);
WIRE 16 -1 (-5225 3150)(-5225 3100);
WIRE 16 -1 (-5400 3150)(-5225 3150);
WIRE 16 -1 (-5400 3100)(-5225 3100);
WIRE 16 -1 (-5225 3100)(-5225 3050);
WIRE 16 -1 (-5225 3050)(-5225 3000);
WIRE 16 -1 (-5400 3050)(-5225 3050);
WIRE 16 -1 (-5225 3000)(-5225 2950);
WIRE 16 -1 (-5400 3000)(-5225 3000);
WIRE 16 -1 (-5225 2950)(-5225 2900);
WIRE 16 -1 (-5400 2950)(-5225 2950);
WIRE 16 -1 (-5225 2900)(-5225 2850);
WIRE 16 -1 (-5400 2900)(-5225 2900);
WIRE 16 -1 (-5225 2850)(-5225 2800);
WIRE 16 -1 (-5400 2850)(-5225 2850);
WIRE 16 -1 (-5225 2800)(-5225 2750);
WIRE 16 -1 (-5400 2800)(-5225 2800);
WIRE 16 -1 (-5225 2750)(-5225 2700);
WIRE 16 -1 (-5400 2750)(-5225 2750);
WIRE 16 -1 (-5225 2700)(-5225 2650);
WIRE 16 -1 (-5400 2700)(-5225 2700);
WIRE 16 -1 (-5225 2650)(-5225 2600);
WIRE 16 -1 (-5400 2650)(-5225 2650);
WIRE 16 -1 (-5400 2600)(-5225 2600);
WIRE 16 -1 (-5225 2600)(-5225 2550);
WIRE 16 -1 (-5225 2550)(-5225 2500);
WIRE 16 -1 (-5400 2550)(-5225 2550);
WIRE 16 -1 (-5225 2500)(-5225 2450);
WIRE 16 -1 (-5400 2500)(-5225 2500);
WIRE 16 -1 (-5225 2450)(-5225 2400);
WIRE 16 -1 (-5400 2450)(-5225 2450);
WIRE 16 -1 (-5225 2400)(-5225 2350);
WIRE 16 -1 (-5400 2400)(-5225 2400);
WIRE 16 -1 (-5225 2350)(-5225 2300);
WIRE 16 -1 (-5400 2350)(-5225 2350);
WIRE 16 -1 (-5225 2300)(-5225 2250);
WIRE 16 -1 (-5400 2300)(-5225 2300);
WIRE 16 -1 (-5225 2250)(-5225 2200);
WIRE 16 -1 (-5400 2250)(-5225 2250);
WIRE 16 -1 (-5225 2200)(-5225 2150);
WIRE 16 -1 (-5400 2200)(-5225 2200);
WIRE 16 -1 (-5225 2150)(-5225 2100);
WIRE 16 -1 (-5400 2150)(-5225 2150);
WIRE 16 -1 (-5225 2100)(-5225 2050);
WIRE 16 -1 (-5400 2100)(-5225 2100);
WIRE 16 -1 (-5400 2050)(-5225 2050);
WIRE 16 -1 (-5225 2050)(-5225 2000);
WIRE 16 -1 (-5225 2000)(-5225 1950);
WIRE 16 -1 (-5400 2000)(-5225 2000);
WIRE 16 -1 (-5225 1950)(-5225 1900);
WIRE 16 -1 (-5400 1950)(-5225 1950);
WIRE 16 -1 (-5225 1900)(-5225 1850);
WIRE 16 -1 (-5400 1900)(-5225 1900);
WIRE 16 -1 (-5225 1850)(-5225 1800);
WIRE 16 -1 (-5400 1850)(-5225 1850);
WIRE 16 -1 (-5225 1800)(-5225 1750);
WIRE 16 -1 (-5400 1800)(-5225 1800);
WIRE 16 -1 (-5225 1750)(-5225 1700);
WIRE 16 -1 (-5400 1750)(-5225 1750);
WIRE 16 -1 (-5225 1700)(-5225 1650);
WIRE 16 -1 (-5400 1700)(-5225 1700);
WIRE 16 -1 (-5225 1650)(-5225 1600);
WIRE 16 -1 (-5400 1650)(-5225 1650);
WIRE 16 -1 (-5225 1600)(-5225 1550);
WIRE 16 -1 (-5400 1600)(-5225 1600);
WIRE 16 -1 (-5400 1550)(-5225 1550);
WIRE 16 -1 (-5225 1550)(-5225 1500);
WIRE 16 -1 (-5225 1500)(-5225 1450);
WIRE 16 -1 (-5400 1500)(-5225 1500);
WIRE 16 -1 (-5225 1450)(-5225 1400);
WIRE 16 -1 (-5400 1450)(-5225 1450);
WIRE 16 -1 (-5225 1400)(-5225 1350);
WIRE 16 -1 (-5400 1400)(-5225 1400);
WIRE 16 -1 (-5225 1350)(-5225 1300);
WIRE 16 -1 (-5400 1350)(-5225 1350);
WIRE 16 -1 (-5225 1300)(-5225 1250);
WIRE 16 -1 (-5400 1300)(-5225 1300);
WIRE 16 -1 (-5225 1250)(-5225 1200);
WIRE 16 -1 (-5400 1250)(-5225 1250);
WIRE 16 -1 (-5225 1200)(-5225 1150);
WIRE 16 -1 (-5400 1200)(-5225 1200);
WIRE 16 -1 (-5225 1150)(-5225 1100);
WIRE 16 -1 (-5400 1150)(-5225 1150);
WIRE 16 -1 (-5225 1100)(-5225 1050);
WIRE 16 -1 (-5400 1100)(-5225 1100);
WIRE 16 -1 (-5400 1050)(-5225 1050);
WIRE 16 -1 (-5225 1050)(-5225 1000);
WIRE 16 -1 (-5225 1000)(-5225 950);
WIRE 16 -1 (-5400 1000)(-5225 1000);
WIRE 16 -1 (-5225 950)(-5225 900);
WIRE 16 -1 (-5400 950)(-5225 950);
WIRE 16 -1 (-5225 900)(-5225 850);
WIRE 16 -1 (-5400 900)(-5225 900);
WIRE 16 -1 (-5225 850)(-5225 800);
WIRE 16 -1 (-5400 850)(-5225 850);
WIRE 16 -1 (-5225 800)(-5225 750);
WIRE 16 -1 (-5400 800)(-5225 800);
WIRE 16 -1 (-5225 750)(-5225 700);
WIRE 16 -1 (-5400 750)(-5225 750);
WIRE 16 -1 (-5225 700)(-5225 650);
WIRE 16 -1 (-5400 700)(-5225 700);
WIRE 16 -1 (-5225 650)(-5225 600);
WIRE 16 -1 (-5400 650)(-5225 650);
WIRE 16 -1 (-5225 600)(-5225 550);
WIRE 16 -1 (-5400 600)(-5225 600);
WIRE 16 -1 (-5400 550)(-5225 550);
WIRE 16 -1 (-5225 550)(-5225 525);
WIRE 16 -1 (-4600 6325)(-4425 6325);
WIRE 16 -1 (-4600 6325)(-4600 6275);
WIRE 16 -1 (-4425 6275)(-4600 6275);
WIRE 16 -1 (-4600 6275)(-4600 6225);
WIRE 16 -1 (-4600 6225)(-4425 6225);
WIRE 16 -1 (-4600 6225)(-4600 6175);
WIRE 16 -1 (-4600 6175)(-4425 6175);
WIRE 16 -1 (-4600 6175)(-4600 6125);
WIRE 16 -1 (-4600 6125)(-4425 6125);
WIRE 16 -1 (-4600 6125)(-4600 6075);
WIRE 16 -1 (-4600 6075)(-4425 6075);
WIRE 16 -1 (-4600 6075)(-4600 6025);
WIRE 16 -1 (-4425 6025)(-4600 6025);
WIRE 16 -1 (-4600 6025)(-4600 5975);
WIRE 16 -1 (-4600 5975)(-4425 5975);
WIRE 16 -1 (-4600 5975)(-4600 5925);
WIRE 16 -1 (-4600 5925)(-4425 5925);
WIRE 16 -1 (-4600 5925)(-4600 5875);
WIRE 16 -1 (-4600 5875)(-4425 5875);
WIRE 16 -1 (-4600 5875)(-4600 5825);
WIRE 16 -1 (-4600 5825)(-4425 5825);
WIRE 16 -1 (-4600 5825)(-4600 5775);
WIRE 16 -1 (-4425 5775)(-4600 5775);
WIRE 16 -1 (-4600 5775)(-4600 5725);
WIRE 16 -1 (-4600 5725)(-4425 5725);
WIRE 16 -1 (-4600 5725)(-4600 5675);
WIRE 16 -1 (-4600 5675)(-4425 5675);
WIRE 16 -1 (-4600 5675)(-4600 5625);
WIRE 16 -1 (-4600 5625)(-4425 5625);
WIRE 16 -1 (-4600 5625)(-4600 5575);
WIRE 16 -1 (-4600 5575)(-4425 5575);
WIRE 16 -1 (-4600 5575)(-4600 5525);
WIRE 16 -1 (-4425 5525)(-4600 5525);
WIRE 16 -1 (-4600 5525)(-4600 5475);
WIRE 16 -1 (-4600 5475)(-4425 5475);
WIRE 16 -1 (-4600 5475)(-4600 5425);
WIRE 16 -1 (-4600 5425)(-4425 5425);
WIRE 16 -1 (-4600 5425)(-4600 5375);
WIRE 16 -1 (-4600 5375)(-4425 5375);
WIRE 16 -1 (-4600 5375)(-4600 5325);
WIRE 16 -1 (-4600 5325)(-4425 5325);
WIRE 16 -1 (-4600 5325)(-4600 5275);
WIRE 16 -1 (-4425 5275)(-4600 5275);
WIRE 16 -1 (-4600 5275)(-4600 5225);
WIRE 16 -1 (-4600 5225)(-4425 5225);
WIRE 16 -1 (-4600 5225)(-4600 5175);
WIRE 16 -1 (-4600 5175)(-4425 5175);
WIRE 16 -1 (-4600 5175)(-4600 5125);
WIRE 16 -1 (-4600 5125)(-4425 5125);
WIRE 16 -1 (-4600 5125)(-4600 5075);
WIRE 16 -1 (-4600 5075)(-4425 5075);
WIRE 16 -1 (-4600 5075)(-4600 5025);
WIRE 16 -1 (-4425 5025)(-4600 5025);
WIRE 16 -1 (-4600 5025)(-4600 4975);
WIRE 16 -1 (-4600 4975)(-4425 4975);
WIRE 16 -1 (-4600 4975)(-4600 4925);
WIRE 16 -1 (-4600 4925)(-4425 4925);
WIRE 16 -1 (-4600 4925)(-4600 4875);
WIRE 16 -1 (-4600 4875)(-4425 4875);
WIRE 16 -1 (-4600 4875)(-4600 4825);
WIRE 16 -1 (-4600 4825)(-4425 4825);
WIRE 16 -1 (-4600 4825)(-4600 4775);
WIRE 16 -1 (-4425 4775)(-4600 4775);
WIRE 16 -1 (-4600 4775)(-4600 4725);
WIRE 16 -1 (-4600 4725)(-4425 4725);
WIRE 16 -1 (-4600 4725)(-4600 4675);
WIRE 16 -1 (-4600 4675)(-4425 4675);
WIRE 16 -1 (-4600 4675)(-4600 4625);
WIRE 16 -1 (-4600 4625)(-4425 4625);
WIRE 16 -1 (-4600 4625)(-4600 4575);
WIRE 16 -1 (-4600 4575)(-4425 4575);
WIRE 16 -1 (-4600 4575)(-4600 4525);
WIRE 16 -1 (-4425 4525)(-4600 4525);
WIRE 16 -1 (-4600 4525)(-4600 4475);
WIRE 16 -1 (-4600 4475)(-4425 4475);
WIRE 16 -1 (-4600 4475)(-4600 4425);
WIRE 16 -1 (-4600 4425)(-4425 4425);
WIRE 16 -1 (-4600 4425)(-4600 4375);
WIRE 16 -1 (-4600 4375)(-4425 4375);
WIRE 16 -1 (-4600 4375)(-4600 4325);
WIRE 16 -1 (-4600 4325)(-4425 4325);
WIRE 16 -1 (-4600 4325)(-4600 4275);
WIRE 16 -1 (-4425 4275)(-4600 4275);
WIRE 16 -1 (-4600 4275)(-4600 4225);
WIRE 16 -1 (-4600 4225)(-4425 4225);
WIRE 16 -1 (-4600 4225)(-4600 4175);
WIRE 16 -1 (-4600 4175)(-4425 4175);
WIRE 16 -1 (-4600 4175)(-4600 4125);
WIRE 16 -1 (-4600 4125)(-4425 4125);
WIRE 16 -1 (-4600 4125)(-4600 4075);
WIRE 16 -1 (-4600 4075)(-4425 4075);
WIRE 16 -1 (-4600 4075)(-4600 4025);
WIRE 16 -1 (-4600 4025)(-4425 4025);
WIRE 16 -1 (-4600 4025)(-4600 3975);
WIRE 16 -1 (-4425 3975)(-4600 3975);
WIRE 16 -1 (-4600 3975)(-4600 3925);
WIRE 16 -1 (-4600 3925)(-4425 3925);
WIRE 16 -1 (-4600 3925)(-4600 3875);
WIRE 16 -1 (-4600 3875)(-4425 3875);
WIRE 16 -1 (-4600 3875)(-4600 3825);
WIRE 16 -1 (-4600 3825)(-4425 3825);
WIRE 16 -1 (-4600 3825)(-4600 3775);
WIRE 16 -1 (-4600 3775)(-4425 3775);
WIRE 16 -1 (-4600 3775)(-4600 3725);
WIRE 16 -1 (-4425 3725)(-4600 3725);
WIRE 16 -1 (-4600 3725)(-4600 3675);
WIRE 16 -1 (-4600 3675)(-4425 3675);
WIRE 16 -1 (-4600 3675)(-4600 3625);
WIRE 16 -1 (-4600 3625)(-4425 3625);
WIRE 16 -1 (-4600 3625)(-4600 3575);
WIRE 16 -1 (-4600 3575)(-4425 3575);
WIRE 16 -1 (-4600 3575)(-4600 3525);
WIRE 16 -1 (-4600 3525)(-4425 3525);
WIRE 16 -1 (-4600 3525)(-4600 3475);
WIRE 16 -1 (-4425 3475)(-4600 3475);
WIRE 16 -1 (-4600 3475)(-4600 3425);
WIRE 16 -1 (-4600 3425)(-4425 3425);
WIRE 16 -1 (-4600 3425)(-4600 3375);
WIRE 16 -1 (-4600 3375)(-4425 3375);
WIRE 16 -1 (-4600 3375)(-4600 3325);
WIRE 16 -1 (-4600 3325)(-4425 3325);
WIRE 16 -1 (-4600 3325)(-4600 3275);
WIRE 16 -1 (-4600 3275)(-4425 3275);
WIRE 16 -1 (-4600 3275)(-4600 3225);
WIRE 16 -1 (-4425 3225)(-4600 3225);
WIRE 16 -1 (-4600 3225)(-4600 3175);
WIRE 16 -1 (-4600 3175)(-4425 3175);
WIRE 16 -1 (-4600 3175)(-4600 3125);
WIRE 16 -1 (-4600 3125)(-4425 3125);
WIRE 16 -1 (-4600 3125)(-4600 3075);
WIRE 16 -1 (-4600 3075)(-4425 3075);
WIRE 16 -1 (-4600 3075)(-4600 3025);
WIRE 16 -1 (-4600 3025)(-4425 3025);
WIRE 16 -1 (-4600 3025)(-4600 2975);
WIRE 16 -1 (-4425 2975)(-4600 2975);
WIRE 16 -1 (-4600 2975)(-4600 2925);
WIRE 16 -1 (-4600 2925)(-4425 2925);
WIRE 16 -1 (-4600 2925)(-4600 2875);
WIRE 16 -1 (-4600 2875)(-4425 2875);
WIRE 16 -1 (-4600 2875)(-4600 2825);
WIRE 16 -1 (-4600 2825)(-4425 2825);
WIRE 16 -1 (-4600 2825)(-4600 2775);
WIRE 16 -1 (-4600 2775)(-4425 2775);
WIRE 16 -1 (-4600 2775)(-4600 2725);
WIRE 16 -1 (-4425 2725)(-4600 2725);
WIRE 16 -1 (-4600 2725)(-4600 2675);
WIRE 16 -1 (-4600 2675)(-4425 2675);
WIRE 16 -1 (-4600 2675)(-4600 2625);
WIRE 16 -1 (-4600 2625)(-4425 2625);
WIRE 16 -1 (-4600 2625)(-4600 2575);
WIRE 16 -1 (-4600 2575)(-4425 2575);
WIRE 16 -1 (-4600 2575)(-4600 2525);
WIRE 16 -1 (-4600 2525)(-4425 2525);
WIRE 16 -1 (-4600 2525)(-4600 2475);
WIRE 16 -1 (-4425 2475)(-4600 2475);
WIRE 16 -1 (-4600 2475)(-4600 2425);
WIRE 16 -1 (-4600 2425)(-4425 2425);
WIRE 16 -1 (-4600 2425)(-4600 2375);
WIRE 16 -1 (-4600 2375)(-4425 2375);
WIRE 16 -1 (-4600 2375)(-4600 2325);
WIRE 16 -1 (-4600 2325)(-4425 2325);
WIRE 16 -1 (-4600 2325)(-4600 2275);
WIRE 16 -1 (-4600 2275)(-4425 2275);
WIRE 16 -1 (-4600 2275)(-4600 2225);
WIRE 16 -1 (-4425 2225)(-4600 2225);
WIRE 16 -1 (-4600 2225)(-4600 2175);
WIRE 16 -1 (-4600 2175)(-4425 2175);
WIRE 16 -1 (-4600 2175)(-4600 2125);
WIRE 16 -1 (-4600 2125)(-4425 2125);
WIRE 16 -1 (-4600 2125)(-4600 2075);
WIRE 16 -1 (-4600 2075)(-4425 2075);
WIRE 16 -1 (-4600 2075)(-4600 2025);
WIRE 16 -1 (-4600 2025)(-4425 2025);
WIRE 16 -1 (-4600 2025)(-4600 1975);
WIRE 16 -1 (-4600 1975)(-4425 1975);
WIRE 16 -1 (-4600 1975)(-4600 1925);
WIRE 16 -1 (-4425 1925)(-4600 1925);
WIRE 16 -1 (-4600 1925)(-4600 1875);
WIRE 16 -1 (-4600 1875)(-4425 1875);
WIRE 16 -1 (-4600 1875)(-4600 1825);
WIRE 16 -1 (-4600 1825)(-4425 1825);
WIRE 16 -1 (-4600 1825)(-4600 1775);
WIRE 16 -1 (-4600 1775)(-4425 1775);
WIRE 16 -1 (-4600 1775)(-4600 1725);
WIRE 16 -1 (-4600 1725)(-4425 1725);
WIRE 16 -1 (-4600 1725)(-4600 1675);
WIRE 16 -1 (-4425 1675)(-4600 1675);
WIRE 16 -1 (-4600 1675)(-4600 1625);
WIRE 16 -1 (-4600 1625)(-4425 1625);
WIRE 16 -1 (-4600 1625)(-4600 1575);
WIRE 16 -1 (-4600 1575)(-4425 1575);
WIRE 16 -1 (-4600 1575)(-4600 1525);
WIRE 16 -1 (-4600 1525)(-4425 1525);
WIRE 16 -1 (-4600 1525)(-4600 1475);
WIRE 16 -1 (-4600 1475)(-4425 1475);
WIRE 16 -1 (-4600 1475)(-4600 1425);
WIRE 16 -1 (-4425 1425)(-4600 1425);
WIRE 16 -1 (-4600 1425)(-4600 1375);
WIRE 16 -1 (-4600 1375)(-4425 1375);
WIRE 16 -1 (-4600 1375)(-4600 1325);
WIRE 16 -1 (-4600 1325)(-4425 1325);
WIRE 16 -1 (-4600 1325)(-4600 1275);
WIRE 16 -1 (-4600 1275)(-4425 1275);
WIRE 16 -1 (-4600 1275)(-4600 1225);
WIRE 16 -1 (-4600 1225)(-4425 1225);
WIRE 16 -1 (-4600 1225)(-4600 1175);
WIRE 16 -1 (-4425 1175)(-4600 1175);
WIRE 16 -1 (-4600 1175)(-4600 1125);
WIRE 16 -1 (-4600 1125)(-4425 1125);
WIRE 16 -1 (-4600 1125)(-4600 1075);
WIRE 16 -1 (-4600 1075)(-4425 1075);
WIRE 16 -1 (-4600 1075)(-4600 1025);
WIRE 16 -1 (-4600 1025)(-4425 1025);
WIRE 16 -1 (-4600 1025)(-4600 975);
WIRE 16 -1 (-4600 975)(-4425 975);
WIRE 16 -1 (-4600 975)(-4600 925);
WIRE 16 -1 (-4425 925)(-4600 925);
WIRE 16 -1 (-4600 925)(-4600 875);
WIRE 16 -1 (-4600 875)(-4425 875);
WIRE 16 -1 (-4600 875)(-4600 825);
WIRE 16 -1 (-4600 825)(-4425 825);
WIRE 16 -1 (-4600 825)(-4600 775);
WIRE 16 -1 (-4600 775)(-4425 775);
WIRE 16 -1 (-4600 775)(-4600 725);
WIRE 16 -1 (-4600 725)(-4425 725);
WIRE 16 -1 (-4600 725)(-4600 675);
WIRE 16 -1 (-4425 675)(-4600 675);
WIRE 16 -1 (-4600 675)(-4600 625);
WIRE 16 -1 (-4600 625)(-4425 625);
WIRE 16 -1 (-4600 625)(-4600 525);
WIRE 16 -1 (-3325 6425)(-3150 6425);
WIRE 16 -1 (-3150 6425)(-3150 6375);
WIRE 16 -1 (-3150 6375)(-3150 6325);
WIRE 16 -1 (-3325 6375)(-3150 6375);
WIRE 16 -1 (-3150 6325)(-3150 6275);
WIRE 16 -1 (-3325 6325)(-3150 6325);
WIRE 16 -1 (-3150 6275)(-3150 6225);
WIRE 16 -1 (-3325 6275)(-3150 6275);
WIRE 16 -1 (-3150 6225)(-3150 6175);
WIRE 16 -1 (-3325 6225)(-3150 6225);
WIRE 16 -1 (-3325 6175)(-3150 6175);
WIRE 16 -1 (-3150 6175)(-3150 6125);
WIRE 16 -1 (-3150 6125)(-3150 6075);
WIRE 16 -1 (-3325 6125)(-3150 6125);
WIRE 16 -1 (-3150 6075)(-3150 6025);
WIRE 16 -1 (-3325 6075)(-3150 6075);
WIRE 16 -1 (-3150 6025)(-3150 5975);
WIRE 16 -1 (-3325 6025)(-3150 6025);
WIRE 16 -1 (-3150 5975)(-3150 5925);
WIRE 16 -1 (-3325 5975)(-3150 5975);
WIRE 16 -1 (-3325 5925)(-3150 5925);
WIRE 16 -1 (-3150 5925)(-3150 5875);
WIRE 16 -1 (-3150 5875)(-3150 5825);
WIRE 16 -1 (-3325 5875)(-3150 5875);
WIRE 16 -1 (-3150 5825)(-3150 5775);
WIRE 16 -1 (-3325 5825)(-3150 5825);
WIRE 16 -1 (-3150 5775)(-3150 5725);
WIRE 16 -1 (-3325 5775)(-3150 5775);
WIRE 16 -1 (-3150 5725)(-3150 5675);
WIRE 16 -1 (-3325 5725)(-3150 5725);
WIRE 16 -1 (-3325 5675)(-3150 5675);
WIRE 16 -1 (-3150 5675)(-3150 5625);
WIRE 16 -1 (-3150 5625)(-3150 5575);
WIRE 16 -1 (-3325 5625)(-3150 5625);
WIRE 16 -1 (-3150 5575)(-3150 5525);
WIRE 16 -1 (-3325 5575)(-3150 5575);
WIRE 16 -1 (-3150 5525)(-3150 5475);
WIRE 16 -1 (-3325 5525)(-3150 5525);
WIRE 16 -1 (-3150 5475)(-3150 5425);
WIRE 16 -1 (-3325 5475)(-3150 5475);
WIRE 16 -1 (-3325 5425)(-3150 5425);
WIRE 16 -1 (-3150 5425)(-3150 5375);
WIRE 16 -1 (-3150 5375)(-3150 5325);
WIRE 16 -1 (-3325 5375)(-3150 5375);
WIRE 16 -1 (-3150 5325)(-3150 5275);
WIRE 16 -1 (-3325 5325)(-3150 5325);
WIRE 16 -1 (-3150 5275)(-3150 5225);
WIRE 16 -1 (-3325 5275)(-3150 5275);
WIRE 16 -1 (-3150 5225)(-3150 5175);
WIRE 16 -1 (-3325 5225)(-3150 5225);
WIRE 16 -1 (-3150 5175)(-3150 5125);
WIRE 16 -1 (-3325 5175)(-3150 5175);
WIRE 16 -1 (-3325 5125)(-3150 5125);
WIRE 16 -1 (-3150 5125)(-3150 5075);
WIRE 16 -1 (-3150 5075)(-3150 5025);
WIRE 16 -1 (-3325 5075)(-3150 5075);
WIRE 16 -1 (-3150 5025)(-3150 4975);
WIRE 16 -1 (-3325 5025)(-3150 5025);
WIRE 16 -1 (-3150 4975)(-3150 4925);
WIRE 16 -1 (-3325 4975)(-3150 4975);
WIRE 16 -1 (-3150 4925)(-3150 4875);
WIRE 16 -1 (-3325 4925)(-3150 4925);
WIRE 16 -1 (-3325 4875)(-3150 4875);
WIRE 16 -1 (-3150 4875)(-3150 4825);
WIRE 16 -1 (-3150 4825)(-3150 4775);
WIRE 16 -1 (-3325 4825)(-3150 4825);
WIRE 16 -1 (-3150 4775)(-3150 4725);
WIRE 16 -1 (-3325 4775)(-3150 4775);
WIRE 16 -1 (-3150 4725)(-3150 4675);
WIRE 16 -1 (-3325 4725)(-3150 4725);
WIRE 16 -1 (-3150 4675)(-3150 4625);
WIRE 16 -1 (-3325 4675)(-3150 4675);
WIRE 16 -1 (-3325 4625)(-3150 4625);
WIRE 16 -1 (-3150 4625)(-3150 4575);
WIRE 16 -1 (-3150 4575)(-3150 4525);
WIRE 16 -1 (-3325 4575)(-3150 4575);
WIRE 16 -1 (-3150 4525)(-3150 4475);
WIRE 16 -1 (-3325 4525)(-3150 4525);
WIRE 16 -1 (-3150 4475)(-3150 4425);
WIRE 16 -1 (-3325 4475)(-3150 4475);
WIRE 16 -1 (-3150 4425)(-3150 4375);
WIRE 16 -1 (-3325 4425)(-3150 4425);
WIRE 16 -1 (-3325 4375)(-3150 4375);
WIRE 16 -1 (-3150 4375)(-3150 4325);
WIRE 16 -1 (-3150 4325)(-3150 4275);
WIRE 16 -1 (-3325 4325)(-3150 4325);
WIRE 16 -1 (-3150 4275)(-3150 4225);
WIRE 16 -1 (-3325 4275)(-3150 4275);
WIRE 16 -1 (-3150 4225)(-3150 4175);
WIRE 16 -1 (-3325 4225)(-3150 4225);
WIRE 16 -1 (-3150 4175)(-3150 4125);
WIRE 16 -1 (-3325 4175)(-3150 4175);
WIRE 16 -1 (-3325 4125)(-3150 4125);
WIRE 16 -1 (-3150 4125)(-3150 4075);
WIRE 16 -1 (-3150 4075)(-3150 4025);
WIRE 16 -1 (-3325 4075)(-3150 4075);
WIRE 16 -1 (-3150 4025)(-3150 3975);
WIRE 16 -1 (-3325 4025)(-3150 4025);
WIRE 16 -1 (-3150 3975)(-3150 3925);
WIRE 16 -1 (-3325 3975)(-3150 3975);
WIRE 16 -1 (-3150 3925)(-3150 3875);
WIRE 16 -1 (-3325 3925)(-3150 3925);
WIRE 16 -1 (-3325 3875)(-3150 3875);
WIRE 16 -1 (-3150 3875)(-3150 3825);
WIRE 16 -1 (-3150 3825)(-3150 3775);
WIRE 16 -1 (-3325 3825)(-3150 3825);
WIRE 16 -1 (-3150 3775)(-3150 3725);
WIRE 16 -1 (-3325 3775)(-3150 3775);
WIRE 16 -1 (-3150 3725)(-3150 3675);
WIRE 16 -1 (-3325 3725)(-3150 3725);
WIRE 16 -1 (-3150 3675)(-3150 3625);
WIRE 16 -1 (-3325 3675)(-3150 3675);
WIRE 16 -1 (-3325 3625)(-3150 3625);
WIRE 16 -1 (-3150 3625)(-3150 3575);
WIRE 16 -1 (-3150 3575)(-3150 3525);
WIRE 16 -1 (-3325 3575)(-3150 3575);
WIRE 16 -1 (-3150 3525)(-3150 3475);
WIRE 16 -1 (-3325 3525)(-3150 3525);
WIRE 16 -1 (-3150 3475)(-3150 3425);
WIRE 16 -1 (-3325 3475)(-3150 3475);
WIRE 16 -1 (-3150 3425)(-3150 3375);
WIRE 16 -1 (-3325 3425)(-3150 3425);
WIRE 16 -1 (-3325 3375)(-3150 3375);
WIRE 16 -1 (-3150 3375)(-3150 3325);
WIRE 16 -1 (-3150 3325)(-3150 3275);
WIRE 16 -1 (-3325 3325)(-3150 3325);
WIRE 16 -1 (-3150 3275)(-3150 3225);
WIRE 16 -1 (-3325 3275)(-3150 3275);
WIRE 16 -1 (-3150 3225)(-3150 3175);
WIRE 16 -1 (-3325 3225)(-3150 3225);
WIRE 16 -1 (-3150 3175)(-3150 3125);
WIRE 16 -1 (-3325 3175)(-3150 3175);
WIRE 16 -1 (-3150 3125)(-3150 3075);
WIRE 16 -1 (-3325 3125)(-3150 3125);
WIRE 16 -1 (-3325 3075)(-3150 3075);
WIRE 16 -1 (-3150 3075)(-3150 3025);
WIRE 16 -1 (-3150 3025)(-3150 2975);
WIRE 16 -1 (-3325 3025)(-3150 3025);
WIRE 16 -1 (-3150 2975)(-3150 2925);
WIRE 16 -1 (-3325 2975)(-3150 2975);
WIRE 16 -1 (-3150 2925)(-3150 2875);
WIRE 16 -1 (-3325 2925)(-3150 2925);
WIRE 16 -1 (-3150 2875)(-3150 2825);
WIRE 16 -1 (-3325 2875)(-3150 2875);
WIRE 16 -1 (-3325 2825)(-3150 2825);
WIRE 16 -1 (-3150 2825)(-3150 2775);
WIRE 16 -1 (-3150 2775)(-3150 2725);
WIRE 16 -1 (-3325 2775)(-3150 2775);
WIRE 16 -1 (-3150 2725)(-3150 2675);
WIRE 16 -1 (-3325 2725)(-3150 2725);
WIRE 16 -1 (-3150 2675)(-3150 2625);
WIRE 16 -1 (-3325 2675)(-3150 2675);
WIRE 16 -1 (-3150 2625)(-3150 2575);
WIRE 16 -1 (-3325 2625)(-3150 2625);
WIRE 16 -1 (-3325 2575)(-3150 2575);
WIRE 16 -1 (-3150 2575)(-3150 2525);
WIRE 16 -1 (-3150 2525)(-3150 2475);
WIRE 16 -1 (-3325 2525)(-3150 2525);
WIRE 16 -1 (-3150 2475)(-3150 2425);
WIRE 16 -1 (-3325 2475)(-3150 2475);
WIRE 16 -1 (-3150 2425)(-3150 2375);
WIRE 16 -1 (-3325 2425)(-3150 2425);
WIRE 16 -1 (-3150 2375)(-3150 2325);
WIRE 16 -1 (-3325 2375)(-3150 2375);
WIRE 16 -1 (-3325 2325)(-3150 2325);
WIRE 16 -1 (-3150 2325)(-3150 2275);
WIRE 16 -1 (-3150 2275)(-3150 2225);
WIRE 16 -1 (-3325 2275)(-3150 2275);
WIRE 16 -1 (-3150 2225)(-3150 2175);
WIRE 16 -1 (-3325 2225)(-3150 2225);
WIRE 16 -1 (-3150 2175)(-3150 2125);
WIRE 16 -1 (-3325 2175)(-3150 2175);
WIRE 16 -1 (-3150 2125)(-3150 2075);
WIRE 16 -1 (-3325 2125)(-3150 2125);
WIRE 16 -1 (-3325 2075)(-3150 2075);
WIRE 16 -1 (-3150 2075)(-3150 2025);
WIRE 16 -1 (-3150 2025)(-3150 1975);
WIRE 16 -1 (-3325 2025)(-3150 2025);
WIRE 16 -1 (-3150 1975)(-3150 1925);
WIRE 16 -1 (-3325 1975)(-3150 1975);
WIRE 16 -1 (-3150 1925)(-3150 1875);
WIRE 16 -1 (-3325 1925)(-3150 1925);
WIRE 16 -1 (-3150 1875)(-3150 1825);
WIRE 16 -1 (-3325 1875)(-3150 1875);
WIRE 16 -1 (-3325 1825)(-3150 1825);
WIRE 16 -1 (-3150 1825)(-3150 1775);
WIRE 16 -1 (-3150 1775)(-3150 1725);
WIRE 16 -1 (-3325 1775)(-3150 1775);
WIRE 16 -1 (-3150 1725)(-3150 1675);
WIRE 16 -1 (-3325 1725)(-3150 1725);
WIRE 16 -1 (-3150 1675)(-3150 1625);
WIRE 16 -1 (-3325 1675)(-3150 1675);
WIRE 16 -1 (-3150 1625)(-3150 1575);
WIRE 16 -1 (-3325 1625)(-3150 1625);
WIRE 16 -1 (-3325 1575)(-3150 1575);
WIRE 16 -1 (-3150 1575)(-3150 1525);
WIRE 16 -1 (-3150 1525)(-3150 1475);
WIRE 16 -1 (-3325 1525)(-3150 1525);
WIRE 16 -1 (-3150 1475)(-3150 1425);
WIRE 16 -1 (-3325 1475)(-3150 1475);
WIRE 16 -1 (-3150 1425)(-3150 1375);
WIRE 16 -1 (-3325 1425)(-3150 1425);
WIRE 16 -1 (-3150 1375)(-3150 1325);
WIRE 16 -1 (-3325 1375)(-3150 1375);
WIRE 16 -1 (-3325 1325)(-3150 1325);
WIRE 16 -1 (-3150 1325)(-3150 1275);
WIRE 16 -1 (-3150 1275)(-3150 1225);
WIRE 16 -1 (-3325 1275)(-3150 1275);
WIRE 16 -1 (-3150 1225)(-3150 1175);
WIRE 16 -1 (-3325 1225)(-3150 1225);
WIRE 16 -1 (-3150 1175)(-3150 1125);
WIRE 16 -1 (-3325 1175)(-3150 1175);
WIRE 16 -1 (-3150 1125)(-3150 1075);
WIRE 16 -1 (-3325 1125)(-3150 1125);
WIRE 16 -1 (-3150 1075)(-3150 1025);
WIRE 16 -1 (-3325 1075)(-3150 1075);
WIRE 16 -1 (-3325 1025)(-3150 1025);
WIRE 16 -1 (-3150 1025)(-3150 975);
WIRE 16 -1 (-3150 975)(-3150 925);
WIRE 16 -1 (-3325 975)(-3150 975);
WIRE 16 -1 (-3150 925)(-3150 875);
WIRE 16 -1 (-3325 925)(-3150 925);
WIRE 16 -1 (-3150 875)(-3150 825);
WIRE 16 -1 (-3325 875)(-3150 875);
WIRE 16 -1 (-3150 825)(-3150 775);
WIRE 16 -1 (-3325 825)(-3150 825);
WIRE 16 -1 (-3325 775)(-3150 775);
WIRE 16 -1 (-3150 775)(-3150 725);
WIRE 16 -1 (-3150 725)(-3150 675);
WIRE 16 -1 (-3325 725)(-3150 725);
WIRE 16 -1 (-3150 675)(-3150 625);
WIRE 16 -1 (-3325 675)(-3150 675);
WIRE 16 -1 (-3325 625)(-3150 625);
WIRE 16 -1 (-3150 500)(-3150 625);
WIRE 16 -1 (-2525 6350)(-2350 6350);
WIRE 16 -1 (-2525 6350)(-2525 6300);
WIRE 16 -1 (-2350 6300)(-2525 6300);
WIRE 16 -1 (-2525 6300)(-2525 6250);
WIRE 16 -1 (-2525 6250)(-2350 6250);
WIRE 16 -1 (-2525 6250)(-2525 6200);
WIRE 16 -1 (-2525 6200)(-2350 6200);
WIRE 16 -1 (-2525 6200)(-2525 6150);
WIRE 16 -1 (-2525 6150)(-2350 6150);
WIRE 16 -1 (-2525 6150)(-2525 6100);
WIRE 16 -1 (-2525 6100)(-2350 6100);
WIRE 16 -1 (-2525 6100)(-2525 6050);
WIRE 16 -1 (-2350 6050)(-2525 6050);
WIRE 16 -1 (-2525 6050)(-2525 6000);
WIRE 16 -1 (-2525 6000)(-2350 6000);
WIRE 16 -1 (-2525 6000)(-2525 5950);
WIRE 16 -1 (-2525 5950)(-2350 5950);
WIRE 16 -1 (-2525 5950)(-2525 5900);
WIRE 16 -1 (-2525 5900)(-2350 5900);
WIRE 16 -1 (-2525 5900)(-2525 5850);
WIRE 16 -1 (-2525 5850)(-2350 5850);
WIRE 16 -1 (-2525 5850)(-2525 5800);
WIRE 16 -1 (-2350 5800)(-2525 5800);
WIRE 16 -1 (-2525 5800)(-2525 5750);
WIRE 16 -1 (-2525 5750)(-2350 5750);
WIRE 16 -1 (-2525 5750)(-2525 5700);
WIRE 16 -1 (-2525 5700)(-2350 5700);
WIRE 16 -1 (-2525 5700)(-2525 5650);
WIRE 16 -1 (-2525 5650)(-2350 5650);
WIRE 16 -1 (-2525 5650)(-2525 5600);
WIRE 16 -1 (-2525 5600)(-2350 5600);
WIRE 16 -1 (-2525 5600)(-2525 5550);
WIRE 16 -1 (-2350 5550)(-2525 5550);
WIRE 16 -1 (-2525 5550)(-2525 5500);
WIRE 16 -1 (-2525 5500)(-2350 5500);
WIRE 16 -1 (-2525 5500)(-2525 5450);
WIRE 16 -1 (-2525 5450)(-2350 5450);
WIRE 16 -1 (-2525 5450)(-2525 5400);
WIRE 16 -1 (-2525 5400)(-2350 5400);
WIRE 16 -1 (-2525 5400)(-2525 5350);
WIRE 16 -1 (-2525 5350)(-2350 5350);
WIRE 16 -1 (-2525 5350)(-2525 5300);
WIRE 16 -1 (-2350 5300)(-2525 5300);
WIRE 16 -1 (-2525 5300)(-2525 5250);
WIRE 16 -1 (-2525 5250)(-2350 5250);
WIRE 16 -1 (-2525 5250)(-2525 5200);
WIRE 16 -1 (-2525 5200)(-2350 5200);
WIRE 16 -1 (-2525 5200)(-2525 5150);
WIRE 16 -1 (-2525 5150)(-2350 5150);
WIRE 16 -1 (-2525 5150)(-2525 5100);
WIRE 16 -1 (-2525 5100)(-2350 5100);
WIRE 16 -1 (-2525 5100)(-2525 5050);
WIRE 16 -1 (-2350 5050)(-2525 5050);
WIRE 16 -1 (-2525 5050)(-2525 5000);
WIRE 16 -1 (-2525 5000)(-2350 5000);
WIRE 16 -1 (-2525 5000)(-2525 4950);
WIRE 16 -1 (-2525 4950)(-2350 4950);
WIRE 16 -1 (-2525 4950)(-2525 4900);
WIRE 16 -1 (-2525 4900)(-2350 4900);
WIRE 16 -1 (-2525 4900)(-2525 4850);
WIRE 16 -1 (-2525 4850)(-2350 4850);
WIRE 16 -1 (-2525 4850)(-2525 4800);
WIRE 16 -1 (-2350 4800)(-2525 4800);
WIRE 16 -1 (-2525 4800)(-2525 4750);
WIRE 16 -1 (-2525 4750)(-2350 4750);
WIRE 16 -1 (-2525 4750)(-2525 4700);
WIRE 16 -1 (-2525 4700)(-2350 4700);
WIRE 16 -1 (-2525 4700)(-2525 4650);
WIRE 16 -1 (-2525 4650)(-2350 4650);
WIRE 16 -1 (-2525 4650)(-2525 4600);
WIRE 16 -1 (-2525 4600)(-2350 4600);
WIRE 16 -1 (-2525 4600)(-2525 4550);
WIRE 16 -1 (-2350 4550)(-2525 4550);
WIRE 16 -1 (-2525 4550)(-2525 4500);
WIRE 16 -1 (-2525 4500)(-2350 4500);
WIRE 16 -1 (-2525 4500)(-2525 4450);
WIRE 16 -1 (-2525 4450)(-2350 4450);
WIRE 16 -1 (-2525 4450)(-2525 4400);
WIRE 16 -1 (-2525 4400)(-2350 4400);
WIRE 16 -1 (-2525 4400)(-2525 4350);
WIRE 16 -1 (-2525 4350)(-2350 4350);
WIRE 16 -1 (-2525 4350)(-2525 4300);
WIRE 16 -1 (-2350 4300)(-2525 4300);
WIRE 16 -1 (-2525 4300)(-2525 4250);
WIRE 16 -1 (-2525 4250)(-2350 4250);
WIRE 16 -1 (-2525 4250)(-2525 4200);
WIRE 16 -1 (-2525 4200)(-2350 4200);
WIRE 16 -1 (-2525 4200)(-2525 4150);
WIRE 16 -1 (-2525 4150)(-2350 4150);
WIRE 16 -1 (-2525 4150)(-2525 4100);
WIRE 16 -1 (-2525 4100)(-2350 4100);
WIRE 16 -1 (-2525 4100)(-2525 4050);
WIRE 16 -1 (-2525 4050)(-2350 4050);
WIRE 16 -1 (-2525 4050)(-2525 4000);
WIRE 16 -1 (-2350 4000)(-2525 4000);
WIRE 16 -1 (-2525 4000)(-2525 3950);
WIRE 16 -1 (-2525 3950)(-2350 3950);
WIRE 16 -1 (-2525 3950)(-2525 3900);
WIRE 16 -1 (-2525 3900)(-2350 3900);
WIRE 16 -1 (-2525 3900)(-2525 3850);
WIRE 16 -1 (-2525 3850)(-2350 3850);
WIRE 16 -1 (-2525 3850)(-2525 3800);
WIRE 16 -1 (-2525 3800)(-2350 3800);
WIRE 16 -1 (-2525 3800)(-2525 3750);
WIRE 16 -1 (-2350 3750)(-2525 3750);
WIRE 16 -1 (-2525 3750)(-2525 3700);
WIRE 16 -1 (-2525 3700)(-2350 3700);
WIRE 16 -1 (-2525 3700)(-2525 3650);
WIRE 16 -1 (-2525 3650)(-2350 3650);
WIRE 16 -1 (-2525 3650)(-2525 3600);
WIRE 16 -1 (-2525 3600)(-2350 3600);
WIRE 16 -1 (-2525 3600)(-2525 3550);
WIRE 16 -1 (-2525 3550)(-2350 3550);
WIRE 16 -1 (-2525 3550)(-2525 3500);
WIRE 16 -1 (-2350 3500)(-2525 3500);
WIRE 16 -1 (-2525 3500)(-2525 3450);
WIRE 16 -1 (-2525 3450)(-2350 3450);
WIRE 16 -1 (-2525 3450)(-2525 3400);
WIRE 16 -1 (-2525 3400)(-2350 3400);
WIRE 16 -1 (-2525 3400)(-2525 3350);
WIRE 16 -1 (-2525 3350)(-2350 3350);
WIRE 16 -1 (-2525 3350)(-2525 3300);
WIRE 16 -1 (-2525 3300)(-2350 3300);
WIRE 16 -1 (-2525 3300)(-2525 3250);
WIRE 16 -1 (-2350 3250)(-2525 3250);
WIRE 16 -1 (-2525 3250)(-2525 3200);
WIRE 16 -1 (-2525 3200)(-2350 3200);
WIRE 16 -1 (-2525 3200)(-2525 3150);
WIRE 16 -1 (-2525 3150)(-2350 3150);
WIRE 16 -1 (-2525 3150)(-2525 3100);
WIRE 16 -1 (-2525 3100)(-2350 3100);
WIRE 16 -1 (-2525 3100)(-2525 3050);
WIRE 16 -1 (-2525 3050)(-2350 3050);
WIRE 16 -1 (-2525 3050)(-2525 3000);
WIRE 16 -1 (-2350 3000)(-2525 3000);
WIRE 16 -1 (-2525 3000)(-2525 2950);
WIRE 16 -1 (-2525 2950)(-2350 2950);
WIRE 16 -1 (-2525 2950)(-2525 2900);
WIRE 16 -1 (-2525 2900)(-2350 2900);
WIRE 16 -1 (-2525 2900)(-2525 2850);
WIRE 16 -1 (-2525 2850)(-2350 2850);
WIRE 16 -1 (-2525 2850)(-2525 2800);
WIRE 16 -1 (-2525 2800)(-2350 2800);
WIRE 16 -1 (-2525 2800)(-2525 2750);
WIRE 16 -1 (-2350 2750)(-2525 2750);
WIRE 16 -1 (-2525 2750)(-2525 2700);
WIRE 16 -1 (-2525 2700)(-2350 2700);
WIRE 16 -1 (-2525 2700)(-2525 2650);
WIRE 16 -1 (-2525 2650)(-2350 2650);
WIRE 16 -1 (-2525 2650)(-2525 2600);
WIRE 16 -1 (-2525 2600)(-2350 2600);
WIRE 16 -1 (-2525 2600)(-2525 2550);
WIRE 16 -1 (-2525 2550)(-2350 2550);
WIRE 16 -1 (-2525 2550)(-2525 2500);
WIRE 16 -1 (-2350 2500)(-2525 2500);
WIRE 16 -1 (-2525 2500)(-2525 2450);
WIRE 16 -1 (-2525 2450)(-2350 2450);
WIRE 16 -1 (-2525 2450)(-2525 2400);
WIRE 16 -1 (-2525 2400)(-2350 2400);
WIRE 16 -1 (-2525 2400)(-2525 2350);
WIRE 16 -1 (-2525 2350)(-2350 2350);
WIRE 16 -1 (-2525 2350)(-2525 2300);
WIRE 16 -1 (-2525 2300)(-2350 2300);
WIRE 16 -1 (-2525 2300)(-2525 2250);
WIRE 16 -1 (-2350 2250)(-2525 2250);
WIRE 16 -1 (-2525 2250)(-2525 2200);
WIRE 16 -1 (-2525 2200)(-2350 2200);
WIRE 16 -1 (-2525 2200)(-2525 2150);
WIRE 16 -1 (-2525 2150)(-2350 2150);
WIRE 16 -1 (-2525 2150)(-2525 2100);
WIRE 16 -1 (-2525 2100)(-2350 2100);
WIRE 16 -1 (-2525 2100)(-2525 2050);
WIRE 16 -1 (-2525 2050)(-2350 2050);
WIRE 16 -1 (-2525 2050)(-2525 2000);
WIRE 16 -1 (-2525 2000)(-2350 2000);
WIRE 16 -1 (-2525 2000)(-2525 1950);
WIRE 16 -1 (-2350 1950)(-2525 1950);
WIRE 16 -1 (-2525 1950)(-2525 1900);
WIRE 16 -1 (-2525 1900)(-2350 1900);
WIRE 16 -1 (-2525 1900)(-2525 1850);
WIRE 16 -1 (-2525 1850)(-2350 1850);
WIRE 16 -1 (-2525 1850)(-2525 1800);
WIRE 16 -1 (-2525 1800)(-2350 1800);
WIRE 16 -1 (-2525 1800)(-2525 1750);
WIRE 16 -1 (-2525 1750)(-2350 1750);
WIRE 16 -1 (-2525 1750)(-2525 1700);
WIRE 16 -1 (-2350 1700)(-2525 1700);
WIRE 16 -1 (-2525 1700)(-2525 1650);
WIRE 16 -1 (-2525 1650)(-2350 1650);
WIRE 16 -1 (-2525 1650)(-2525 1600);
WIRE 16 -1 (-2525 1600)(-2350 1600);
WIRE 16 -1 (-2525 1600)(-2525 1550);
WIRE 16 -1 (-2525 1550)(-2350 1550);
WIRE 16 -1 (-2525 1550)(-2525 1500);
WIRE 16 -1 (-2525 1500)(-2350 1500);
WIRE 16 -1 (-2525 1500)(-2525 1450);
WIRE 16 -1 (-2350 1450)(-2525 1450);
WIRE 16 -1 (-2525 1450)(-2525 1400);
WIRE 16 -1 (-2525 1400)(-2350 1400);
WIRE 16 -1 (-2525 1400)(-2525 1350);
WIRE 16 -1 (-2525 1350)(-2350 1350);
WIRE 16 -1 (-2525 1350)(-2525 1300);
WIRE 16 -1 (-2525 1300)(-2350 1300);
WIRE 16 -1 (-2525 1300)(-2525 1250);
WIRE 16 -1 (-2525 1250)(-2350 1250);
WIRE 16 -1 (-2525 1250)(-2525 1200);
WIRE 16 -1 (-2350 1200)(-2525 1200);
WIRE 16 -1 (-2525 1200)(-2525 1150);
WIRE 16 -1 (-2525 1150)(-2350 1150);
WIRE 16 -1 (-2525 1150)(-2525 1100);
WIRE 16 -1 (-2525 1100)(-2350 1100);
WIRE 16 -1 (-2525 1100)(-2525 1050);
WIRE 16 -1 (-2525 1050)(-2350 1050);
WIRE 16 -1 (-2525 1050)(-2525 1000);
WIRE 16 -1 (-2525 1000)(-2350 1000);
WIRE 16 -1 (-2525 1000)(-2525 950);
WIRE 16 -1 (-2350 950)(-2525 950);
WIRE 16 -1 (-2525 950)(-2525 900);
WIRE 16 -1 (-2525 900)(-2350 900);
WIRE 16 -1 (-2525 900)(-2525 850);
WIRE 16 -1 (-2525 850)(-2350 850);
WIRE 16 -1 (-2525 850)(-2525 800);
WIRE 16 -1 (-2525 800)(-2350 800);
WIRE 16 -1 (-2525 800)(-2525 750);
WIRE 16 -1 (-2525 750)(-2350 750);
WIRE 16 -1 (-2525 750)(-2525 700);
WIRE 16 -1 (-2350 700)(-2525 700);
WIRE 16 -1 (-2525 700)(-2525 650);
WIRE 16 -1 (-2525 650)(-2350 650);
WIRE 16 -1 (-2525 650)(-2525 600);
WIRE 16 -1 (-2350 600)(-2525 600);
WIRE 16 -1 (-2525 600)(-2525 550);
WIRE 16 -1 (-2350 550)(-2525 550);
WIRE 16 -1 (-2525 550)(-2525 500);
WIRE 16 -1 (-1250 6350)(-1075 6350);
WIRE 16 -1 (-1075 6350)(-1075 6300);
WIRE 16 -1 (-1075 6300)(-1075 6250);
WIRE 16 -1 (-1250 6300)(-1075 6300);
WIRE 16 -1 (-1075 6250)(-1075 6200);
WIRE 16 -1 (-1250 6250)(-1075 6250);
WIRE 16 -1 (-1075 6200)(-1075 6150);
WIRE 16 -1 (-1250 6200)(-1075 6200);
WIRE 16 -1 (-1250 6150)(-1075 6150);
WIRE 16 -1 (-1075 6150)(-1075 6100);
WIRE 16 -1 (-1075 6100)(-1075 6050);
WIRE 16 -1 (-1250 6100)(-1075 6100);
WIRE 16 -1 (-1075 6050)(-1075 6000);
WIRE 16 -1 (-1250 6050)(-1075 6050);
WIRE 16 -1 (-1075 6000)(-1075 5950);
WIRE 16 -1 (-1250 6000)(-1075 6000);
WIRE 16 -1 (-1075 5950)(-1075 5900);
WIRE 16 -1 (-1250 5950)(-1075 5950);
WIRE 16 -1 (-1250 5900)(-1075 5900);
WIRE 16 -1 (-1075 5900)(-1075 5850);
WIRE 16 -1 (-1075 5850)(-1075 5800);
WIRE 16 -1 (-1250 5850)(-1075 5850);
WIRE 16 -1 (-1075 5800)(-1075 5750);
WIRE 16 -1 (-1250 5800)(-1075 5800);
WIRE 16 -1 (-1075 5750)(-1075 5700);
WIRE 16 -1 (-1250 5750)(-1075 5750);
WIRE 16 -1 (-1075 5700)(-1075 5650);
WIRE 16 -1 (-1250 5700)(-1075 5700);
WIRE 16 -1 (-1250 5650)(-1075 5650);
WIRE 16 -1 (-1075 5650)(-1075 5600);
WIRE 16 -1 (-1075 5600)(-1075 5550);
WIRE 16 -1 (-1250 5600)(-1075 5600);
WIRE 16 -1 (-1075 5550)(-1075 5500);
WIRE 16 -1 (-1250 5550)(-1075 5550);
WIRE 16 -1 (-1075 5500)(-1075 5450);
WIRE 16 -1 (-1250 5500)(-1075 5500);
WIRE 16 -1 (-1075 5450)(-1075 5400);
WIRE 16 -1 (-1250 5450)(-1075 5450);
WIRE 16 -1 (-1250 5400)(-1075 5400);
WIRE 16 -1 (-1075 5400)(-1075 5350);
WIRE 16 -1 (-1075 5350)(-1075 5300);
WIRE 16 -1 (-1250 5350)(-1075 5350);
WIRE 16 -1 (-1075 5300)(-1075 5250);
WIRE 16 -1 (-1250 5300)(-1075 5300);
WIRE 16 -1 (-1075 5250)(-1075 5200);
WIRE 16 -1 (-1250 5250)(-1075 5250);
WIRE 16 -1 (-1075 5200)(-1075 5150);
WIRE 16 -1 (-1250 5200)(-1075 5200);
WIRE 16 -1 (-1250 5150)(-1075 5150);
WIRE 16 -1 (-1075 5150)(-1075 5100);
WIRE 16 -1 (-1075 5100)(-1075 5050);
WIRE 16 -1 (-1250 5100)(-1075 5100);
WIRE 16 -1 (-1075 5050)(-1075 5000);
WIRE 16 -1 (-1250 5050)(-1075 5050);
WIRE 16 -1 (-1075 5000)(-1075 4950);
WIRE 16 -1 (-1250 5000)(-1075 5000);
WIRE 16 -1 (-1075 4950)(-1075 4900);
WIRE 16 -1 (-1250 4950)(-1075 4950);
WIRE 16 -1 (-1250 4900)(-1075 4900);
WIRE 16 -1 (-1075 4900)(-1075 4850);
WIRE 16 -1 (-1075 4850)(-1075 4800);
WIRE 16 -1 (-1250 4850)(-1075 4850);
WIRE 16 -1 (-1075 4800)(-1075 4750);
WIRE 16 -1 (-1250 4800)(-1075 4800);
WIRE 16 -1 (-1075 4750)(-1075 4700);
WIRE 16 -1 (-1250 4750)(-1075 4750);
WIRE 16 -1 (-1075 4700)(-1075 4650);
WIRE 16 -1 (-1250 4700)(-1075 4700);
WIRE 16 -1 (-1250 4650)(-1075 4650);
WIRE 16 -1 (-1075 4650)(-1075 4600);
WIRE 16 -1 (-1075 4600)(-1075 4550);
WIRE 16 -1 (-1250 4600)(-1075 4600);
WIRE 16 -1 (-1075 4550)(-1075 4500);
WIRE 16 -1 (-1250 4550)(-1075 4550);
WIRE 16 -1 (-1075 4500)(-1075 4450);
WIRE 16 -1 (-1250 4500)(-1075 4500);
WIRE 16 -1 (-1075 4450)(-1075 4400);
WIRE 16 -1 (-1250 4450)(-1075 4450);
WIRE 16 -1 (-1250 4400)(-1075 4400);
WIRE 16 -1 (-1075 4400)(-1075 4350);
WIRE 16 -1 (-1075 4350)(-1075 4300);
WIRE 16 -1 (-1250 4350)(-1075 4350);
WIRE 16 -1 (-1075 4300)(-1075 4250);
WIRE 16 -1 (-1250 4300)(-1075 4300);
WIRE 16 -1 (-1075 4250)(-1075 4200);
WIRE 16 -1 (-1250 4250)(-1075 4250);
WIRE 16 -1 (-1075 4200)(-1075 4150);
WIRE 16 -1 (-1250 4200)(-1075 4200);
WIRE 16 -1 (-1075 4150)(-1075 4100);
WIRE 16 -1 (-1250 4150)(-1075 4150);
WIRE 16 -1 (-1250 4100)(-1075 4100);
WIRE 16 -1 (-1075 4100)(-1075 4050);
WIRE 16 -1 (-1075 4050)(-1075 4000);
WIRE 16 -1 (-1250 4050)(-1075 4050);
WIRE 16 -1 (-1075 4000)(-1075 3950);
WIRE 16 -1 (-1250 4000)(-1075 4000);
WIRE 16 -1 (-1075 3950)(-1075 3900);
WIRE 16 -1 (-1250 3950)(-1075 3950);
WIRE 16 -1 (-1075 3900)(-1075 3850);
WIRE 16 -1 (-1250 3900)(-1075 3900);
WIRE 16 -1 (-1250 3850)(-1075 3850);
WIRE 16 -1 (-1075 3850)(-1075 3800);
WIRE 16 -1 (-1075 3800)(-1075 3750);
WIRE 16 -1 (-1250 3800)(-1075 3800);
WIRE 16 -1 (-1075 3750)(-1075 3700);
WIRE 16 -1 (-1250 3750)(-1075 3750);
WIRE 16 -1 (-1075 3700)(-1075 3650);
WIRE 16 -1 (-1250 3700)(-1075 3700);
WIRE 16 -1 (-1075 3650)(-1075 3600);
WIRE 16 -1 (-1250 3650)(-1075 3650);
WIRE 16 -1 (-1250 3600)(-1075 3600);
WIRE 16 -1 (-1075 3600)(-1075 3550);
WIRE 16 -1 (-1075 3550)(-1075 3500);
WIRE 16 -1 (-1250 3550)(-1075 3550);
WIRE 16 -1 (-1075 3500)(-1075 3450);
WIRE 16 -1 (-1250 3500)(-1075 3500);
WIRE 16 -1 (-1075 3450)(-1075 3400);
WIRE 16 -1 (-1250 3450)(-1075 3450);
WIRE 16 -1 (-1075 3400)(-1075 3350);
WIRE 16 -1 (-1250 3400)(-1075 3400);
WIRE 16 -1 (-1250 3350)(-1075 3350);
WIRE 16 -1 (-1075 3350)(-1075 3300);
WIRE 16 -1 (-1075 3300)(-1075 3250);
WIRE 16 -1 (-1250 3300)(-1075 3300);
WIRE 16 -1 (-1075 3250)(-1075 3200);
WIRE 16 -1 (-1250 3250)(-1075 3250);
WIRE 16 -1 (-1075 3200)(-1075 3150);
WIRE 16 -1 (-1250 3200)(-1075 3200);
WIRE 16 -1 (-1075 3150)(-1075 3100);
WIRE 16 -1 (-1250 3150)(-1075 3150);
WIRE 16 -1 (-1250 3100)(-1075 3100);
WIRE 16 -1 (-1075 3100)(-1075 3050);
WIRE 16 -1 (-1075 3050)(-1075 3000);
WIRE 16 -1 (-1250 3050)(-1075 3050);
WIRE 16 -1 (-1075 3000)(-1075 2950);
WIRE 16 -1 (-1250 3000)(-1075 3000);
WIRE 16 -1 (-1075 2950)(-1075 2900);
WIRE 16 -1 (-1250 2950)(-1075 2950);
WIRE 16 -1 (-1075 2900)(-1075 2850);
WIRE 16 -1 (-1250 2900)(-1075 2900);
WIRE 16 -1 (-1250 2850)(-1075 2850);
WIRE 16 -1 (-1075 2850)(-1075 2800);
WIRE 16 -1 (-1075 2800)(-1075 2750);
WIRE 16 -1 (-1250 2800)(-1075 2800);
WIRE 16 -1 (-1075 2750)(-1075 2700);
WIRE 16 -1 (-1250 2750)(-1075 2750);
WIRE 16 -1 (-1075 2700)(-1075 2650);
WIRE 16 -1 (-1250 2700)(-1075 2700);
WIRE 16 -1 (-1075 2650)(-1075 2600);
WIRE 16 -1 (-1250 2650)(-1075 2650);
WIRE 16 -1 (-1250 2600)(-1075 2600);
WIRE 16 -1 (-1075 2600)(-1075 2550);
WIRE 16 -1 (-1075 2550)(-1075 2500);
WIRE 16 -1 (-1250 2550)(-1075 2550);
WIRE 16 -1 (-1075 2500)(-1075 2450);
WIRE 16 -1 (-1250 2500)(-1075 2500);
WIRE 16 -1 (-1075 2450)(-1075 2400);
WIRE 16 -1 (-1250 2450)(-1075 2450);
WIRE 16 -1 (-1075 2400)(-1075 2350);
WIRE 16 -1 (-1250 2400)(-1075 2400);
WIRE 16 -1 (-1250 2350)(-1075 2350);
WIRE 16 -1 (-1075 2350)(-1075 2300);
WIRE 16 -1 (-1075 2300)(-1075 2250);
WIRE 16 -1 (-1250 2300)(-1075 2300);
WIRE 16 -1 (-1075 2250)(-1075 2200);
WIRE 16 -1 (-1250 2250)(-1075 2250);
WIRE 16 -1 (-1075 2200)(-1075 2150);
WIRE 16 -1 (-1250 2200)(-1075 2200);
WIRE 16 -1 (-1075 2150)(-1075 2100);
WIRE 16 -1 (-1250 2150)(-1075 2150);
WIRE 16 -1 (-1075 2100)(-1075 2050);
WIRE 16 -1 (-1250 2100)(-1075 2100);
WIRE 16 -1 (-1250 2050)(-1075 2050);
WIRE 16 -1 (-1075 2050)(-1075 2000);
WIRE 16 -1 (-1075 2000)(-1075 1950);
WIRE 16 -1 (-1250 2000)(-1075 2000);
WIRE 16 -1 (-1075 1950)(-1075 1900);
WIRE 16 -1 (-1250 1950)(-1075 1950);
WIRE 16 -1 (-1075 1900)(-1075 1850);
WIRE 16 -1 (-1250 1900)(-1075 1900);
WIRE 16 -1 (-1075 1850)(-1075 1800);
WIRE 16 -1 (-1250 1850)(-1075 1850);
WIRE 16 -1 (-1250 1800)(-1075 1800);
WIRE 16 -1 (-1075 1800)(-1075 1750);
WIRE 16 -1 (-1075 1750)(-1075 1700);
WIRE 16 -1 (-1250 1750)(-1075 1750);
WIRE 16 -1 (-1075 1700)(-1075 1650);
WIRE 16 -1 (-1250 1700)(-1075 1700);
WIRE 16 -1 (-1075 1650)(-1075 1600);
WIRE 16 -1 (-1250 1650)(-1075 1650);
WIRE 16 -1 (-1075 1600)(-1075 1550);
WIRE 16 -1 (-1250 1600)(-1075 1600);
WIRE 16 -1 (-1250 1550)(-1075 1550);
WIRE 16 -1 (-1075 1550)(-1075 1500);
WIRE 16 -1 (-1075 1500)(-1075 1450);
WIRE 16 -1 (-1250 1500)(-1075 1500);
WIRE 16 -1 (-1075 1450)(-1075 1400);
WIRE 16 -1 (-1250 1450)(-1075 1450);
WIRE 16 -1 (-1075 1400)(-1075 1350);
WIRE 16 -1 (-1250 1400)(-1075 1400);
WIRE 16 -1 (-1075 1350)(-1075 1300);
WIRE 16 -1 (-1250 1350)(-1075 1350);
WIRE 16 -1 (-1250 1300)(-1075 1300);
WIRE 16 -1 (-1075 1300)(-1075 1250);
WIRE 16 -1 (-1075 1250)(-1075 1200);
WIRE 16 -1 (-1250 1250)(-1075 1250);
WIRE 16 -1 (-1075 1200)(-1075 1150);
WIRE 16 -1 (-1250 1200)(-1075 1200);
WIRE 16 -1 (-1075 1150)(-1075 1100);
WIRE 16 -1 (-1250 1150)(-1075 1150);
WIRE 16 -1 (-1075 1100)(-1075 1050);
WIRE 16 -1 (-1250 1100)(-1075 1100);
WIRE 16 -1 (-1250 1050)(-1075 1050);
WIRE 16 -1 (-1075 1050)(-1075 1000);
WIRE 16 -1 (-1075 1000)(-1075 950);
WIRE 16 -1 (-1250 1000)(-1075 1000);
WIRE 16 -1 (-1075 950)(-1075 900);
WIRE 16 -1 (-1250 950)(-1075 950);
WIRE 16 -1 (-1075 900)(-1075 850);
WIRE 16 -1 (-1250 900)(-1075 900);
WIRE 16 -1 (-1075 850)(-1075 800);
WIRE 16 -1 (-1250 850)(-1075 850);
WIRE 16 -1 (-1250 800)(-1075 800);
WIRE 16 -1 (-1075 800)(-1075 750);
WIRE 16 -1 (-1075 750)(-1075 700);
WIRE 16 -1 (-1250 750)(-1075 750);
WIRE 16 -1 (-1075 700)(-1075 650);
WIRE 16 -1 (-1250 700)(-1075 700);
WIRE 16 -1 (-1075 650)(-1075 600);
WIRE 16 -1 (-1250 650)(-1075 650);
WIRE 16 -1 (-1075 600)(-1075 550);
WIRE 16 -1 (-1250 600)(-1075 600);
WIRE 16 -1 (-1250 550)(-1075 550);
WIRE 16 -1 (-1075 500)(-1075 550);
DOT 1 (-6675 5900);
DOT 1 (-6675 3750);
DOT 1 (-6675 3650);
DOT 1 (-7250 5150);
DOT 1 (-6675 4950);
DOT 1 (-5225 4150);
DOT 1 (-8700 550);
DOT 1 (-8700 600);
DOT 1 (-8700 650);
DOT 1 (-8700 700);
DOT 1 (-8700 750);
DOT 1 (-8700 800);
DOT 1 (-8700 850);
DOT 1 (-8700 900);
DOT 1 (-8700 950);
DOT 1 (-8700 1000);
DOT 1 (-8700 1050);
DOT 1 (-8700 1100);
DOT 1 (-8700 1150);
DOT 1 (-8700 1200);
DOT 1 (-8700 1250);
DOT 1 (-8700 1300);
DOT 1 (-8700 1350);
DOT 1 (-8700 1400);
DOT 1 (-8700 1450);
DOT 1 (-8700 1500);
DOT 1 (-8700 1550);
DOT 1 (-8700 1600);
DOT 1 (-8700 1700);
DOT 1 (-8700 1800);
DOT 1 (-8700 1750);
DOT 1 (-8700 1850);
DOT 1 (-8700 1900);
DOT 1 (-8700 1950);
DOT 1 (-8700 2000);
DOT 1 (-8700 2050);
DOT 1 (-8700 2100);
DOT 1 (-8700 2150);
DOT 1 (-8700 2200);
DOT 1 (-8700 2250);
DOT 1 (-8700 2300);
DOT 1 (-8700 2350);
DOT 1 (-8700 2400);
DOT 1 (-8700 2450);
DOT 1 (-8700 2500);
DOT 1 (-8700 2550);
DOT 1 (-8700 2600);
DOT 1 (-8700 2650);
DOT 1 (-8700 2700);
DOT 1 (-8700 2750);
DOT 1 (-8700 2800);
DOT 1 (-8700 2850);
DOT 1 (-8700 2900);
DOT 1 (-8700 2950);
DOT 1 (-8700 3000);
DOT 1 (-8700 3050);
DOT 1 (-8700 3100);
DOT 1 (-8700 3150);
DOT 1 (-8700 3250);
DOT 1 (-8700 3200);
DOT 1 (-8700 3300);
DOT 1 (-8700 3350);
DOT 1 (-8700 3400);
DOT 1 (-8700 3450);
DOT 1 (-8700 3500);
DOT 1 (-8700 3600);
DOT 1 (-8700 3550);
DOT 1 (-8700 3650);
DOT 1 (-8700 3700);
DOT 1 (-8700 3750);
DOT 1 (-8700 3800);
DOT 1 (-8700 3850);
DOT 1 (-8700 3900);
DOT 1 (-8700 3950);
DOT 1 (-8700 4000);
DOT 1 (-8700 4050);
DOT 1 (-8700 4150);
DOT 1 (-8700 4200);
DOT 1 (-8700 4250);
DOT 1 (-8700 4300);
DOT 1 (-8700 4350);
DOT 1 (-8700 4400);
DOT 1 (-8700 4450);
DOT 1 (-8700 4500);
DOT 1 (-8700 4550);
DOT 1 (-8700 4600);
DOT 1 (-8700 4650);
DOT 1 (-8700 4700);
DOT 1 (-8700 4750);
DOT 1 (-8700 4800);
DOT 1 (-8700 4850);
DOT 1 (-8700 4900);
DOT 1 (-8700 4950);
DOT 1 (-8700 5000);
DOT 1 (-8700 5050);
DOT 1 (-8700 5100);
DOT 1 (-8700 5150);
DOT 1 (-8700 5200);
DOT 1 (-8700 5250);
DOT 1 (-8700 5300);
DOT 1 (-8700 5350);
DOT 1 (-8700 5400);
DOT 1 (-8700 5450);
DOT 1 (-8700 5500);
DOT 1 (-8700 5550);
DOT 1 (-8700 5600);
DOT 1 (-8700 5650);
DOT 1 (-8700 5700);
DOT 1 (-8700 5750);
DOT 1 (-8700 5800);
DOT 1 (-8700 5850);
DOT 1 (-8700 5900);
DOT 1 (-8700 5950);
DOT 1 (-8700 6000);
DOT 1 (-8700 6050);
DOT 1 (-8700 6100);
DOT 1 (-8700 6150);
DOT 1 (-8700 6200);
DOT 1 (-8700 6250);
DOT 1 (-8700 6300);
DOT 1 (-8700 6350);
DOT 1 (-8700 6400);
DOT 1 (-7250 650);
DOT 1 (-7250 600);
DOT 1 (-7250 700);
DOT 1 (-7250 800);
DOT 1 (-7250 750);
DOT 1 (-7250 900);
DOT 1 (-7250 850);
DOT 1 (-7250 950);
DOT 1 (-7250 1050);
DOT 1 (-7250 1000);
DOT 1 (-6675 550);
DOT 1 (-6675 600);
DOT 1 (-6675 650);
DOT 1 (-6675 700);
DOT 1 (-6675 750);
DOT 1 (-6675 800);
DOT 1 (-6675 850);
DOT 1 (-6675 900);
DOT 1 (-6675 950);
DOT 1 (-6675 1050);
DOT 1 (-6675 1000);
DOT 1 (-7250 1100);
DOT 1 (-7250 1150);
DOT 1 (-7250 1200);
DOT 1 (-7250 1250);
DOT 1 (-7250 1300);
DOT 1 (-7250 1400);
DOT 1 (-7250 1450);
DOT 1 (-7250 1350);
DOT 1 (-7250 1500);
DOT 1 (-7250 1550);
DOT 1 (-7250 1600);
DOT 1 (-7250 1700);
DOT 1 (-7250 1750);
DOT 1 (-7250 1800);
DOT 1 (-7250 1850);
DOT 1 (-7250 1950);
DOT 1 (-7250 1900);
DOT 1 (-7250 2000);
DOT 1 (-7250 2050);
DOT 1 (-6675 1100);
DOT 1 (-6675 1150);
DOT 1 (-6675 1200);
DOT 1 (-6675 1250);
DOT 1 (-6675 1300);
DOT 1 (-6675 1350);
DOT 1 (-6675 1400);
DOT 1 (-6675 1450);
DOT 1 (-6675 1500);
DOT 1 (-6675 1550);
DOT 1 (-6675 1600);
DOT 1 (-6675 1650);
DOT 1 (-6675 1700);
DOT 1 (-6675 1750);
DOT 1 (-6675 1800);
DOT 1 (-6675 1850);
DOT 1 (-6675 1900);
DOT 1 (-6675 2050);
DOT 1 (-7250 2100);
DOT 1 (-7250 2200);
DOT 1 (-7250 2150);
DOT 1 (-7250 2350);
DOT 1 (-7250 2300);
DOT 1 (-7250 2250);
DOT 1 (-7250 2450);
DOT 1 (-7250 2400);
DOT 1 (-7250 2600);
DOT 1 (-7250 2550);
DOT 1 (-7250 2500);
DOT 1 (-7250 2700);
DOT 1 (-7250 2650);
DOT 1 (-7250 2750);
DOT 1 (-7250 2850);
DOT 1 (-7250 2800);
DOT 1 (-7250 2950);
DOT 1 (-7250 2900);
DOT 1 (-7250 3000);
DOT 1 (-7250 3100);
DOT 1 (-7250 3050);
DOT 1 (-6675 2150);
DOT 1 (-6675 2200);
DOT 1 (-6675 2250);
DOT 1 (-6675 2300);
DOT 1 (-6675 2350);
DOT 1 (-6675 2400);
DOT 1 (-6675 2450);
DOT 1 (-6675 2550);
DOT 1 (-6675 2500);
DOT 1 (-6675 2600);
DOT 1 (-6675 2650);
DOT 1 (-6675 2700);
DOT 1 (-6675 2750);
DOT 1 (-6675 2800);
DOT 1 (-6675 2850);
DOT 1 (-6675 2900);
DOT 1 (-6675 2950);
DOT 1 (-6675 3000);
DOT 1 (-6675 3100);
DOT 1 (-6675 3050);
DOT 1 (-7250 3150);
DOT 1 (-7250 3200);
DOT 1 (-7250 3250);
DOT 1 (-7250 3300);
DOT 1 (-7250 3350);
DOT 1 (-7250 3450);
DOT 1 (-7250 3500);
DOT 1 (-7250 3400);
DOT 1 (-7250 3550);
DOT 1 (-7250 3600);
DOT 1 (-7250 3700);
DOT 1 (-7250 3750);
DOT 1 (-7250 3650);
DOT 1 (-7250 3800);
DOT 1 (-7250 3850);
DOT 1 (-7250 3900);
DOT 1 (-7250 4000);
DOT 1 (-7250 3950);
DOT 1 (-7250 4050);
DOT 1 (-7250 4100);
DOT 1 (-6675 3150);
DOT 1 (-6675 3200);
DOT 1 (-6675 3250);
DOT 1 (-6675 3300);
DOT 1 (-6675 3350);
DOT 1 (-6675 3400);
DOT 1 (-6675 3450);
DOT 1 (-6675 3500);
DOT 1 (-6675 3600);
DOT 1 (-6675 3550);
DOT 1 (-6675 3700);
DOT 1 (-6675 3800);
DOT 1 (-6675 3850);
DOT 1 (-6675 3900);
DOT 1 (-6675 3950);
DOT 1 (-6675 4000);
DOT 1 (-6675 4050);
DOT 1 (-6675 4100);
DOT 1 (-5225 550);
DOT 1 (-5225 650);
DOT 1 (-5225 600);
DOT 1 (-5225 700);
DOT 1 (-5225 750);
DOT 1 (-5225 800);
DOT 1 (-5225 850);
DOT 1 (-5225 900);
DOT 1 (-5225 950);
DOT 1 (-5225 1000);
DOT 1 (-5225 1050);
DOT 1 (-4600 675);
DOT 1 (-4600 625);
DOT 1 (-4600 725);
DOT 1 (-4600 775);
DOT 1 (-4600 825);
DOT 1 (-4600 875);
DOT 1 (-4600 925);
DOT 1 (-4600 975);
DOT 1 (-4600 1025);
DOT 1 (-4600 1075);
DOT 1 (-5225 1100);
DOT 1 (-5225 1150);
DOT 1 (-5225 1200);
DOT 1 (-5225 1250);
DOT 1 (-5225 1300);
DOT 1 (-5225 1350);
DOT 1 (-5225 1400);
DOT 1 (-5225 1450);
DOT 1 (-5225 1500);
DOT 1 (-5225 1550);
DOT 1 (-5225 1600);
DOT 1 (-5225 1650);
DOT 1 (-5225 1700);
DOT 1 (-5225 1750);
DOT 1 (-5225 1800);
DOT 1 (-5225 1850);
DOT 1 (-5225 1900);
DOT 1 (-5225 1950);
DOT 1 (-5225 2000);
DOT 1 (-5225 2050);
DOT 1 (-4600 1125);
DOT 1 (-4600 1175);
DOT 1 (-4600 1225);
DOT 1 (-4600 1275);
DOT 1 (-4600 1325);
DOT 1 (-4600 1375);
DOT 1 (-4600 1425);
DOT 1 (-4600 1475);
DOT 1 (-4600 1525);
DOT 1 (-4600 1575);
DOT 1 (-4600 1625);
DOT 1 (-4600 1675);
DOT 1 (-4600 1725);
DOT 1 (-4600 1775);
DOT 1 (-4600 1825);
DOT 1 (-4600 1925);
DOT 1 (-4600 1875);
DOT 1 (-4600 1975);
DOT 1 (-4600 2025);
DOT 1 (-4600 2075);
DOT 1 (-5225 2100);
DOT 1 (-5225 2150);
DOT 1 (-5225 2200);
DOT 1 (-5225 2250);
DOT 1 (-5225 2300);
DOT 1 (-5225 2350);
DOT 1 (-5225 2400);
DOT 1 (-5225 2450);
DOT 1 (-5225 2500);
DOT 1 (-5225 2550);
DOT 1 (-5225 2600);
DOT 1 (-5225 2650);
DOT 1 (-5225 2700);
DOT 1 (-5225 2750);
DOT 1 (-5225 2800);
DOT 1 (-5225 2850);
DOT 1 (-5225 2900);
DOT 1 (-5225 2950);
DOT 1 (-5225 3000);
DOT 1 (-5225 3050);
DOT 1 (-5225 3100);
DOT 1 (-4600 2125);
DOT 1 (-4600 2175);
DOT 1 (-4600 2225);
DOT 1 (-4600 2275);
DOT 1 (-4600 2325);
DOT 1 (-4600 2375);
DOT 1 (-4600 2425);
DOT 1 (-4600 2475);
DOT 1 (-4600 2525);
DOT 1 (-4600 2575);
DOT 1 (-4600 2625);
DOT 1 (-4600 2675);
DOT 1 (-4600 2725);
DOT 1 (-4600 2775);
DOT 1 (-4600 2825);
DOT 1 (-4600 2875);
DOT 1 (-4600 2925);
DOT 1 (-4600 2975);
DOT 1 (-4600 3025);
DOT 1 (-4600 3075);
DOT 1 (-4600 3125);
DOT 1 (-5225 3150);
DOT 1 (-5225 3250);
DOT 1 (-5225 3200);
DOT 1 (-5225 3350);
DOT 1 (-5225 3300);
DOT 1 (-5225 3450);
DOT 1 (-5225 3500);
DOT 1 (-5225 3600);
DOT 1 (-5225 3550);
DOT 1 (-5225 3650);
DOT 1 (-5225 3700);
DOT 1 (-5225 3750);
DOT 1 (-5225 3800);
DOT 1 (-5225 3850);
DOT 1 (-5225 3900);
DOT 1 (-5225 3950);
DOT 1 (-5225 4000);
DOT 1 (-5225 4100);
DOT 1 (-5225 4050);
DOT 1 (-4600 3175);
DOT 1 (-4600 3225);
DOT 1 (-4600 3275);
DOT 1 (-4600 3325);
DOT 1 (-4600 3375);
DOT 1 (-4600 3425);
DOT 1 (-4600 3475);
DOT 1 (-4600 3525);
DOT 1 (-4600 3575);
DOT 1 (-4600 3625);
DOT 1 (-4600 3675);
DOT 1 (-4600 3725);
DOT 1 (-4600 3775);
DOT 1 (-4600 3825);
DOT 1 (-4600 3875);
DOT 1 (-4600 3925);
DOT 1 (-4600 3975);
DOT 1 (-4600 4025);
DOT 1 (-4600 4075);
DOT 1 (-4600 4125);
DOT 1 (-7250 4150);
DOT 1 (-6675 4150);
DOT 1 (-7250 4250);
DOT 1 (-7250 4200);
DOT 1 (-7250 4350);
DOT 1 (-7250 4400);
DOT 1 (-7250 4300);
DOT 1 (-7250 4450);
DOT 1 (-7250 4650);
DOT 1 (-7250 4550);
DOT 1 (-7250 4700);
DOT 1 (-7250 4750);
DOT 1 (-7250 4800);
DOT 1 (-7250 4850);
DOT 1 (-7250 4900);
DOT 1 (-7250 5000);
DOT 1 (-7250 4950);
DOT 1 (-7250 5050);
DOT 1 (-7250 5100);
DOT 1 (-6675 4200);
DOT 1 (-6675 4250);
DOT 1 (-6675 4300);
DOT 1 (-6675 4350);
DOT 1 (-6675 4400);
DOT 1 (-6675 4450);
DOT 1 (-6675 4500);
DOT 1 (-6675 4600);
DOT 1 (-6675 4550);
DOT 1 (-6675 4650);
DOT 1 (-6675 4700);
DOT 1 (-6675 4750);
DOT 1 (-6675 4800);
DOT 1 (-6675 4850);
DOT 1 (-6675 4900);
DOT 1 (-6675 5000);
DOT 1 (-6675 5050);
DOT 1 (-6675 5150);
DOT 1 (-6675 5100);
DOT 1 (-7250 5250);
DOT 1 (-7250 5200);
DOT 1 (-7250 5300);
DOT 1 (-7250 5400);
DOT 1 (-7250 5350);
DOT 1 (-7250 5500);
DOT 1 (-7250 5550);
DOT 1 (-7250 5450);
DOT 1 (-7250 5600);
DOT 1 (-7250 5650);
DOT 1 (-7250 5750);
DOT 1 (-7250 5800);
DOT 1 (-7250 5700);
DOT 1 (-7250 5850);
DOT 1 (-7250 5900);
DOT 1 (-7250 5950);
DOT 1 (-7250 6050);
DOT 1 (-7250 6000);
DOT 1 (-7250 6100);
DOT 1 (-7250 6150);
DOT 1 (-6675 5200);
DOT 1 (-6675 5250);
DOT 1 (-6675 5300);
DOT 1 (-6675 5350);
DOT 1 (-6675 5400);
DOT 1 (-6675 5450);
DOT 1 (-6675 5500);
DOT 1 (-6675 5550);
DOT 1 (-6675 5600);
DOT 1 (-6675 5650);
DOT 1 (-6675 5700);
DOT 1 (-6675 5750);
DOT 1 (-6675 5800);
DOT 1 (-6675 5850);
DOT 1 (-6675 6000);
DOT 1 (-6675 6050);
DOT 1 (-6675 6100);
DOT 1 (-6675 6150);
DOT 1 (-6675 6200);
DOT 1 (-7250 6200);
DOT 1 (-7250 6250);
DOT 1 (-7250 6400);
DOT 1 (-7250 6350);
DOT 1 (-6675 6300);
DOT 1 (-5225 4200);
DOT 1 (-5225 4250);
DOT 1 (-5225 4300);
DOT 1 (-5225 4350);
DOT 1 (-5225 4400);
DOT 1 (-5225 4500);
DOT 1 (-5225 4450);
DOT 1 (-5225 4550);
DOT 1 (-5225 4600);
DOT 1 (-5225 4650);
DOT 1 (-5225 4700);
DOT 1 (-5225 4750);
DOT 1 (-5225 4800);
DOT 1 (-5225 4850);
DOT 1 (-5225 4900);
DOT 1 (-5225 4950);
DOT 1 (-5225 5000);
DOT 1 (-5225 5050);
DOT 1 (-5225 5100);
DOT 1 (-5225 5150);
DOT 1 (-4600 4175);
DOT 1 (-4600 4225);
DOT 1 (-4600 4275);
DOT 1 (-4600 4325);
DOT 1 (-4600 4375);
DOT 1 (-4600 4425);
DOT 1 (-4600 4475);
DOT 1 (-4600 4525);
DOT 1 (-4600 4625);
DOT 1 (-4600 4575);
DOT 1 (-4600 4675);
DOT 1 (-4600 4725);
DOT 1 (-4600 4775);
DOT 1 (-4600 4825);
DOT 1 (-4600 4875);
DOT 1 (-4600 4925);
DOT 1 (-4600 4975);
DOT 1 (-4600 5025);
DOT 1 (-4600 5075);
DOT 1 (-4600 5125);
DOT 1 (-4600 5175);
DOT 1 (-5225 5200);
DOT 1 (-5225 5250);
DOT 1 (-5225 5300);
DOT 1 (-5225 5350);
DOT 1 (-5225 5400);
DOT 1 (-5225 5500);
DOT 1 (-5225 5550);
DOT 1 (-5225 5650);
DOT 1 (-5225 5600);
DOT 1 (-5225 5700);
DOT 1 (-5225 5750);
DOT 1 (-5225 5800);
DOT 1 (-5225 5850);
DOT 1 (-5225 5900);
DOT 1 (-5225 5950);
DOT 1 (-5225 6000);
DOT 1 (-5225 6050);
DOT 1 (-5225 6100);
DOT 1 (-5225 6150);
DOT 1 (-4600 5225);
DOT 1 (-4600 5275);
DOT 1 (-4600 5325);
DOT 1 (-4600 5375);
DOT 1 (-4600 5425);
DOT 1 (-4600 5475);
DOT 1 (-4600 5525);
DOT 1 (-4600 5575);
DOT 1 (-4600 5625);
DOT 1 (-4600 5675);
DOT 1 (-4600 5725);
DOT 1 (-4600 5775);
DOT 1 (-4600 5825);
DOT 1 (-4600 5875);
DOT 1 (-4600 5925);
DOT 1 (-4600 5975);
DOT 1 (-4600 6025);
DOT 1 (-4600 6075);
DOT 1 (-4600 6125);
DOT 1 (-4600 6175);
DOT 1 (-5225 6200);
DOT 1 (-5225 6250);
DOT 1 (-5225 6300);
DOT 1 (-4600 6225);
DOT 1 (-4600 6275);
DOT 1 (-3150 625);
DOT 1 (-3150 675);
DOT 1 (-3150 775);
DOT 1 (-3150 725);
DOT 1 (-3150 825);
DOT 1 (-3150 925);
DOT 1 (-3150 875);
DOT 1 (-3150 1025);
DOT 1 (-3150 975);
DOT 1 (-2525 550);
DOT 1 (-2525 600);
DOT 1 (-2525 650);
DOT 1 (-2525 700);
DOT 1 (-2525 750);
DOT 1 (-2525 800);
DOT 1 (-2525 850);
DOT 1 (-2525 900);
DOT 1 (-2525 950);
DOT 1 (-2525 1000);
DOT 1 (-2525 1050);
DOT 1 (-3150 1075);
DOT 1 (-3150 1175);
DOT 1 (-3150 1125);
DOT 1 (-3150 1325);
DOT 1 (-3150 1275);
DOT 1 (-3150 1225);
DOT 1 (-3150 1425);
DOT 1 (-3150 1375);
DOT 1 (-3150 1575);
DOT 1 (-3150 1525);
DOT 1 (-3150 1475);
DOT 1 (-3150 1625);
DOT 1 (-3150 1675);
DOT 1 (-3150 1725);
DOT 1 (-3150 1825);
DOT 1 (-3150 1775);
DOT 1 (-3150 1925);
DOT 1 (-3150 1875);
DOT 1 (-3150 1975);
DOT 1 (-3150 2075);
DOT 1 (-3150 2025);
DOT 1 (-2525 1100);
DOT 1 (-2525 1150);
DOT 1 (-2525 1200);
DOT 1 (-2525 1250);
DOT 1 (-2525 1300);
DOT 1 (-2525 1350);
DOT 1 (-2525 1400);
DOT 1 (-2525 1450);
DOT 1 (-2525 1500);
DOT 1 (-2525 1550);
DOT 1 (-2525 1600);
DOT 1 (-2525 1650);
DOT 1 (-2525 1700);
DOT 1 (-2525 1750);
DOT 1 (-2525 1800);
DOT 1 (-2525 1850);
DOT 1 (-2525 1900);
DOT 1 (-2525 1950);
DOT 1 (-2525 2000);
DOT 1 (-2525 2050);
DOT 1 (-2525 2100);
DOT 1 (-3150 2225);
DOT 1 (-3150 2175);
DOT 1 (-3150 2125);
DOT 1 (-3150 2325);
DOT 1 (-3150 2275);
DOT 1 (-3150 2425);
DOT 1 (-3150 2475);
DOT 1 (-3150 2375);
DOT 1 (-3150 2575);
DOT 1 (-3150 2525);
DOT 1 (-3150 2675);
DOT 1 (-3150 2725);
DOT 1 (-3150 2625);
DOT 1 (-3150 2775);
DOT 1 (-3150 2825);
DOT 1 (-3150 2875);
DOT 1 (-3150 2975);
DOT 1 (-3150 2925);
DOT 1 (-3150 3025);
DOT 1 (-3150 3075);
DOT 1 (-2525 2150);
DOT 1 (-2525 2200);
DOT 1 (-2525 2250);
DOT 1 (-2525 2300);
DOT 1 (-2525 2350);
DOT 1 (-2525 2400);
DOT 1 (-2525 2450);
DOT 1 (-2525 2500);
DOT 1 (-2525 2550);
DOT 1 (-2525 2600);
DOT 1 (-2525 2700);
DOT 1 (-2525 2650);
DOT 1 (-2525 2750);
DOT 1 (-2525 2800);
DOT 1 (-2525 2850);
DOT 1 (-2525 2900);
DOT 1 (-2525 2950);
DOT 1 (-2525 3000);
DOT 1 (-2525 3050);
DOT 1 (-2525 3100);
DOT 1 (-3150 3125);
DOT 1 (-3150 3225);
DOT 1 (-3150 3175);
DOT 1 (-3150 3375);
DOT 1 (-3150 3325);
DOT 1 (-3150 3275);
DOT 1 (-3150 3425);
DOT 1 (-3150 3475);
DOT 1 (-3150 3625);
DOT 1 (-3150 3575);
DOT 1 (-3150 3525);
DOT 1 (-3150 3675);
DOT 1 (-3150 3725);
DOT 1 (-3150 3775);
DOT 1 (-3150 3875);
DOT 1 (-3150 3825);
DOT 1 (-3150 3975);
DOT 1 (-3150 3925);
DOT 1 (-3150 4025);
DOT 1 (-3150 4125);
DOT 1 (-3150 4075);
DOT 1 (-2525 3150);
DOT 1 (-2525 3200);
DOT 1 (-2525 3250);
DOT 1 (-2525 3300);
DOT 1 (-2525 3350);
DOT 1 (-2525 3400);
DOT 1 (-2525 3450);
DOT 1 (-2525 3500);
DOT 1 (-2525 3550);
DOT 1 (-2525 3600);
DOT 1 (-2525 3650);
DOT 1 (-2525 3700);
DOT 1 (-2525 3750);
DOT 1 (-2525 3800);
DOT 1 (-2525 3850);
DOT 1 (-2525 3900);
DOT 1 (-2525 3950);
DOT 1 (-2525 4000);
DOT 1 (-2525 4050);
DOT 1 (-2525 4100);
DOT 1 (-1075 550);
DOT 1 (-1075 650);
DOT 1 (-1075 600);
DOT 1 (-1075 700);
DOT 1 (-1075 750);
DOT 1 (-1075 800);
DOT 1 (-1075 900);
DOT 1 (-1075 850);
DOT 1 (-1075 950);
DOT 1 (-1075 1000);
DOT 1 (-1075 1050);
DOT 1 (-1075 1100);
DOT 1 (-1075 1150);
DOT 1 (-1075 1200);
DOT 1 (-1075 1300);
DOT 1 (-1075 1250);
DOT 1 (-1075 1350);
DOT 1 (-1075 1400);
DOT 1 (-1075 1450);
DOT 1 (-1075 1550);
DOT 1 (-1075 1500);
DOT 1 (-1075 1650);
DOT 1 (-1075 1600);
DOT 1 (-1075 1700);
DOT 1 (-1075 1800);
DOT 1 (-1075 1750);
DOT 1 (-1075 1850);
DOT 1 (-1075 1900);
DOT 1 (-1075 1950);
DOT 1 (-1075 2050);
DOT 1 (-1075 2000);
DOT 1 (-1075 2100);
DOT 1 (-1075 2150);
DOT 1 (-1075 2200);
DOT 1 (-1075 2250);
DOT 1 (-1075 2300);
DOT 1 (-1075 2350);
DOT 1 (-1075 2450);
DOT 1 (-1075 2400);
DOT 1 (-1075 2500);
DOT 1 (-1075 2550);
DOT 1 (-1075 2600);
DOT 1 (-1075 2700);
DOT 1 (-1075 2650);
DOT 1 (-1075 2750);
DOT 1 (-1075 2800);
DOT 1 (-1075 2850);
DOT 1 (-1075 2950);
DOT 1 (-1075 2900);
DOT 1 (-1075 3000);
DOT 1 (-1075 3050);
DOT 1 (-1075 3100);
DOT 1 (-1075 3150);
DOT 1 (-1075 3200);
DOT 1 (-1075 3250);
DOT 1 (-1075 3300);
DOT 1 (-1075 3350);
DOT 1 (-1075 3400);
DOT 1 (-1075 3450);
DOT 1 (-1075 3500);
DOT 1 (-1075 3550);
DOT 1 (-1075 3600);
DOT 1 (-1075 3650);
DOT 1 (-1075 3700);
DOT 1 (-1075 3750);
DOT 1 (-1075 3850);
DOT 1 (-1075 3800);
DOT 1 (-1075 3900);
DOT 1 (-1075 3950);
DOT 1 (-1075 4000);
DOT 1 (-1075 4100);
DOT 1 (-1075 4050);
DOT 1 (-2525 4150);
DOT 1 (-1075 4150);
DOT 1 (-3150 4225);
DOT 1 (-3150 4175);
DOT 1 (-3150 4275);
DOT 1 (-3150 4375);
DOT 1 (-3150 4325);
DOT 1 (-3150 4525);
DOT 1 (-3150 4475);
DOT 1 (-3150 4425);
DOT 1 (-3150 4575);
DOT 1 (-3150 4625);
DOT 1 (-3150 4725);
DOT 1 (-3150 4775);
DOT 1 (-3150 4675);
DOT 1 (-3150 4875);
DOT 1 (-3150 4825);
DOT 1 (-3150 4925);
DOT 1 (-3150 5025);
DOT 1 (-3150 4975);
DOT 1 (-3150 5075);
DOT 1 (-3150 5125);
DOT 1 (-2525 4200);
DOT 1 (-2525 4250);
DOT 1 (-2525 4300);
DOT 1 (-2525 4350);
DOT 1 (-2525 4400);
DOT 1 (-2525 4450);
DOT 1 (-2525 4500);
DOT 1 (-2525 4550);
DOT 1 (-2525 4600);
DOT 1 (-2525 4650);
DOT 1 (-2525 4750);
DOT 1 (-2525 4700);
DOT 1 (-2525 4800);
DOT 1 (-2525 4850);
DOT 1 (-2525 4900);
DOT 1 (-2525 4950);
DOT 1 (-2525 5000);
DOT 1 (-2525 5050);
DOT 1 (-2525 5100);
DOT 1 (-2525 5150);
DOT 1 (-3150 5175);
DOT 1 (-3150 5275);
DOT 1 (-3150 5225);
DOT 1 (-3150 5425);
DOT 1 (-3150 5375);
DOT 1 (-3150 5325);
DOT 1 (-3150 5475);
DOT 1 (-3150 5525);
DOT 1 (-3150 5675);
DOT 1 (-3150 5625);
DOT 1 (-3150 5575);
DOT 1 (-3150 5725);
DOT 1 (-3150 5775);
DOT 1 (-3150 5925);
DOT 1 (-3150 5875);
DOT 1 (-3150 5825);
DOT 1 (-3150 6025);
DOT 1 (-3150 5975);
DOT 1 (-3150 6075);
DOT 1 (-3150 6175);
DOT 1 (-3150 6125);
DOT 1 (-2525 5250);
DOT 1 (-2525 5200);
DOT 1 (-2525 5300);
DOT 1 (-2525 5350);
DOT 1 (-2525 5400);
DOT 1 (-2525 5450);
DOT 1 (-2525 5500);
DOT 1 (-2525 5550);
DOT 1 (-2525 5600);
DOT 1 (-2525 5650);
DOT 1 (-2525 5700);
DOT 1 (-2525 5750);
DOT 1 (-2525 5800);
DOT 1 (-2525 5850);
DOT 1 (-2525 5900);
DOT 1 (-2525 5950);
DOT 1 (-2525 6000);
DOT 1 (-2525 6050);
DOT 1 (-2525 6100);
DOT 1 (-2525 6150);
DOT 1 (-2525 6200);
DOT 1 (-3150 6225);
DOT 1 (-3150 6275);
DOT 1 (-3150 6325);
DOT 1 (-3150 6375);
DOT 1 (-2525 6250);
DOT 1 (-2525 6300);
DOT 1 (-1075 4200);
DOT 1 (-1075 4250);
DOT 1 (-1075 4300);
DOT 1 (-1075 4350);
DOT 1 (-1075 4400);
DOT 1 (-1075 4450);
DOT 1 (-1075 4500);
DOT 1 (-1075 4550);
DOT 1 (-1075 4600);
DOT 1 (-1075 4650);
DOT 1 (-1075 4750);
DOT 1 (-1075 4700);
DOT 1 (-1075 4850);
DOT 1 (-1075 4800);
DOT 1 (-1075 4900);
DOT 1 (-1075 5000);
DOT 1 (-1075 4950);
DOT 1 (-1075 5050);
DOT 1 (-1075 5100);
DOT 1 (-1075 5150);
DOT 1 (-1075 5250);
DOT 1 (-1075 5200);
DOT 1 (-1075 5300);
DOT 1 (-1075 5350);
DOT 1 (-1075 5400);
DOT 1 (-1075 5450);
DOT 1 (-1075 5500);
DOT 1 (-1075 5550);
DOT 1 (-1075 5600);
DOT 1 (-1075 5650);
DOT 1 (-1075 5700);
DOT 1 (-1075 5750);
DOT 1 (-1075 5800);
DOT 1 (-1075 5900);
DOT 1 (-1075 5850);
DOT 1 (-1075 5950);
DOT 1 (-1075 6000);
DOT 1 (-1075 6050);
DOT 1 (-1075 6150);
DOT 1 (-1075 6100);
DOT 1 (-1075 6200);
DOT 1 (-1075 6250);
DOT 1 (-1075 6300);
DOT 1 (-8700 1650);
DOT 1 (-8700 4100);
DOT 1 (-5225 3400);
DOT 1 (-5225 5450);
DOT 1 (-7250 1650);
DOT 1 (-6675 1950);
DOT 1 (-6675 2000);
DOT 1 (-6675 2100);
DOT 1 (-7250 4500);
DOT 1 (-7250 4600);
DOT 1 (-6675 6350);
DOT 1 (-6675 6250);
DOT 1 (-6675 5950);
DOT 1 (-7250 6300);
QUIT
